FILE_TYPE = MACRO_DRAWING;
SET COLOR_WIRE YELLOW;
SET COLOR_PROP ORANGE;
SET COLOR_DOT WHITE;
SET COLOR_ARC YELLOW;
SET COLOR_BODY GREEN;
SET COLOR_NOTE PURPLE;
SET PROP_DISPLAY VALUE;
SET PAGE_NUMBER P160;
FORCEADD Q_RES..2
(-4950 2725);
FORCEPROP 1 LAST PART_NUMBER CS31002FB08
J 0
(-4910 2600);
DISPLAY 0.510638 (-4910 2600);
DISPLAY INVISIBLE (-4910 2600);
FORCEPROP 1 LAST VALUE 10K
J 0
(-4905 2800);
DISPLAY 0.510638 (-4905 2800);
FORCEPROP 1 LAST TOLERANCE 1%
J 0
(-4905 2750);
DISPLAY 0.510638 (-4905 2750);
FORCEPROP 1 LAST MATERIAL CHIP
J 0
(-4910 2650);
DISPLAY 0.510638 (-4910 2650);
FORCEPROP 1 LAST WATTAGE 1/16W
J 0
(-4910 2700);
DISPLAY 0.510638 (-4910 2700);
FORCEPROP 1 LAST PACK_TYPE 0402LF
J 0
(-4910 2550);
DISPLAY 0.510638 (-4910 2550);
FORCEPROP 1 LAST $LOCATION R3457
J 0
(-4905 2850);
DISPLAY 0.978723 (-4905 2850);
FORCEPROP 1 LASTPIN (-4950 2825) $PN 1
J 0
(-4945 2787);
DISPLAY 0.787234 (-4945 2787);
PAINT MONO (-4945 2787);
FORCEPROP 1 LASTPIN (-4950 2625) $PN 2
J 0
(-4945 2635);
DISPLAY 0.787234 (-4945 2635);
PAINT MONO (-4945 2635);
FORCEPROP 1 LAST PATH I123
J 0
(-4900 2900);
DISPLAY 0.978723 (-4900 2900);
PAINT WHITE (-4900 2900);
DISPLAY INVISIBLE (-4900 2900);
FORCEPROP 2 LAST CDS_LIB pure_quanta
J 0
(-4950 2725);
DISPLAY INVISIBLE (-4950 2725);
FORCEPROP 0 LAST CDS_LOCATION R3457
J 0
(-4900 2900);
DISPLAY 1.021277 (-4900 2900);
DISPLAY INVISIBLE (-4900 2900);
FORCEPROP 0 LAST $SEC 1
J 0
(-4900 2900);
DISPLAY 0.680851 (-4900 2900);
PAINT MONO (-4900 2900);
DISPLAY INVISIBLE (-4900 2900);
FORCEPROP 0 LAST CDS_SEC 1
J 0
(-4900 2900);
DISPLAY 1.021277 (-4900 2900);
DISPLAY INVISIBLE (-4900 2900);
FORCEADD Q_RES..2
(-4975 3225);
FORCEPROP 1 LAST PART_NUMBER CS41002FB09
J 0
(-4935 3100);
DISPLAY 0.510638 (-4935 3100);
DISPLAY INVISIBLE (-4935 3100);
FORCEPROP 1 LAST MATERIAL EMPTY
J 0
(-4935 3150);
DISPLAY 0.510638 (-4935 3150);
PAINT RED (-4935 3150);
FORCEPROP 1 LAST WATTAGE 1/16W
J 0
(-4935 3200);
DISPLAY 0.510638 (-4935 3200);
FORCEPROP 1 LAST TOLERANCE 1%
J 0
(-4930 3250);
DISPLAY 0.510638 (-4930 3250);
FORCEPROP 1 LAST VALUE 100K
J 0
(-4930 3300);
DISPLAY 0.510638 (-4930 3300);
FORCEPROP 1 LAST PACK_TYPE 0402LF
J 0
(-4935 3050);
DISPLAY 0.510638 (-4935 3050);
FORCEPROP 1 LAST $LOCATION R3456
J 0
(-4930 3350);
DISPLAY 0.978723 (-4930 3350);
FORCEPROP 1 LASTPIN (-4975 3325) $PN 1
J 0
(-4970 3287);
DISPLAY 0.787234 (-4970 3287);
PAINT MONO (-4970 3287);
FORCEPROP 1 LASTPIN (-4975 3125) $PN 2
J 0
(-4970 3135);
DISPLAY 0.787234 (-4970 3135);
PAINT MONO (-4970 3135);
FORCEPROP 1 LAST PATH I124
J 0
(-4925 3400);
DISPLAY 0.978723 (-4925 3400);
PAINT WHITE (-4925 3400);
DISPLAY INVISIBLE (-4925 3400);
FORCEPROP 2 LAST CDS_LIB pure_quanta
J 0
(-4975 3225);
DISPLAY INVISIBLE (-4975 3225);
FORCEPROP 0 LAST CDS_LOCATION R3456
J 0
(-4925 3400);
DISPLAY 1.021277 (-4925 3400);
DISPLAY INVISIBLE (-4925 3400);
FORCEPROP 0 LAST $SEC 1
J 0
(-4925 3400);
DISPLAY 0.680851 (-4925 3400);
PAINT MONO (-4925 3400);
DISPLAY INVISIBLE (-4925 3400);
FORCEPROP 0 LAST CDS_SEC 1
J 0
(-4925 3400);
DISPLAY 1.021277 (-4925 3400);
DISPLAY INVISIBLE (-4925 3400);
FORCEADD UNIVERSAL_POWER..1
(-4975 3525);
FORCEPROP 3 LASTPIN (-4975 3475) SIG_NAME P3V3_AUX\g
J 0
(-4965 3485);
DISPLAY 0.659574 (-4965 3485);
PAINT MONO (-4965 3485);
DISPLAY INVISIBLE (-4965 3485);
FORCEPROP 1 LAST HDL_POWER P3V3_AUX
J 1
(-4975 3575);
DISPLAY 0.872340 (-4975 3575);
PAINT GREEN (-4975 3575);
FORCEPROP 2 LAST CDS_LIB logical_power
J 0
(-4975 3525);
DISPLAY INVISIBLE (-4975 3525);
FORCEPROP 1 LAST PATH I125
J 0
(-4925 3550);
DISPLAY 0.872340 (-4925 3550);
PAINT AQUA (-4925 3550);
DISPLAY INVISIBLE (-4925 3550);
FORCEADD UNIVERSAL_GND..1
(-4950 2500);
FORCEPROP 3 LASTPIN (-4950 2550) SIG_NAME GND\g
J 0
(-4940 2560);
DISPLAY 0.659574 (-4940 2560);
PAINT MONO (-4940 2560);
DISPLAY INVISIBLE (-4940 2560);
FORCEPROP 1 LAST HDL_POWER GND
J 1
(-4925 2425);
DISPLAY 0.872340 (-4925 2425);
PAINT GREEN (-4925 2425);
DISPLAY INVISIBLE (-4925 2425);
FORCEPROP 1 LAST PATH I126
J 0
(-4875 2500);
DISPLAY 0.872340 (-4875 2500);
PAINT AQUA (-4875 2500);
DISPLAY INVISIBLE (-4875 2500);
FORCEPROP 2 LAST CDS_LIB logical_power
J 0
(-4950 2500);
DISPLAY INVISIBLE (-4950 2500);
FORCEADD Q_RES..2
(-7600 3350);
FORCEPROP 1 LAST PART_NUMBER CS24702JB10
J 0
(-7560 3175);
DISPLAY 0.638298 (-7560 3175);
DISPLAY INVISIBLE (-7560 3175);
FORCEPROP 1 LAST VALUE 4.7K
J 0
(-7555 3425);
DISPLAY 0.638298 (-7555 3425);
FORCEPROP 1 LAST MATERIAL EMPTY
J 0
(-7560 3275);
DISPLAY 0.638298 (-7560 3275);
PAINT RED (-7560 3275);
FORCEPROP 1 LAST WATTAGE 1/16W
J 0
(-7560 3325);
DISPLAY 0.638298 (-7560 3325);
FORCEPROP 1 LAST TOLERANCE 5%
J 0
(-7555 3375);
DISPLAY 0.638298 (-7555 3375);
FORCEPROP 1 LAST PACK_TYPE 0402LF
J 0
(-7560 3225);
DISPLAY 0.638298 (-7560 3225);
FORCEPROP 1 LAST $LOCATION R3451
J 0
(-7555 3475);
DISPLAY 0.978723 (-7555 3475);
FORCEPROP 1 LASTPIN (-7600 3450) $PN 1
J 0
(-7595 3412);
DISPLAY 0.787234 (-7595 3412);
PAINT MONO (-7595 3412);
FORCEPROP 1 LASTPIN (-7600 3250) $PN 2
J 0
(-7595 3260);
DISPLAY 0.787234 (-7595 3260);
PAINT MONO (-7595 3260);
FORCEPROP 2 LAST CDS_LIB pure_quanta
J 0
(-7600 3350);
DISPLAY INVISIBLE (-7600 3350);
FORCEPROP 1 LAST PATH I127
J 0
(-7550 3525);
DISPLAY 0.978723 (-7550 3525);
PAINT WHITE (-7550 3525);
DISPLAY INVISIBLE (-7550 3525);
FORCEPROP 0 LAST CDS_LOCATION R3451
J 0
(-7550 3525);
DISPLAY 1.021277 (-7550 3525);
DISPLAY INVISIBLE (-7550 3525);
FORCEPROP 0 LAST $SEC 1
J 0
(-7550 3525);
DISPLAY 0.680851 (-7550 3525);
PAINT MONO (-7550 3525);
DISPLAY INVISIBLE (-7550 3525);
FORCEPROP 0 LAST CDS_SEC 1
J 0
(-7550 3525);
DISPLAY 1.021277 (-7550 3525);
DISPLAY INVISIBLE (-7550 3525);
FORCEADD UNIVERSAL_GND..1
(-6225 1050);
FORCEPROP 3 LASTPIN (-6225 1100) SIG_NAME GND\g
J 0
(-6215 1110);
DISPLAY 0.659574 (-6215 1110);
PAINT MONO (-6215 1110);
DISPLAY INVISIBLE (-6215 1110);
FORCEPROP 1 LAST HDL_POWER GND
J 1
(-6200 975);
DISPLAY 0.872340 (-6200 975);
PAINT GREEN (-6200 975);
DISPLAY INVISIBLE (-6200 975);
FORCEPROP 2 LAST CDS_LIB logical_power
J 0
(-6225 1050);
DISPLAY INVISIBLE (-6225 1050);
FORCEPROP 1 LAST PATH I137
J 0
(-6150 1050);
DISPLAY 0.872340 (-6150 1050);
PAINT AQUA (-6150 1050);
DISPLAY INVISIBLE (-6150 1050);
FORCEADD UNIVERSAL_GND..1
(-4950 750);
FORCEPROP 3 LASTPIN (-4950 800) SIG_NAME GND\g
J 0
(-4940 810);
DISPLAY 0.659574 (-4940 810);
PAINT MONO (-4940 810);
DISPLAY INVISIBLE (-4940 810);
FORCEPROP 1 LAST HDL_POWER GND
J 1
(-4925 675);
DISPLAY 0.872340 (-4925 675);
PAINT GREEN (-4925 675);
DISPLAY INVISIBLE (-4925 675);
FORCEPROP 2 LAST CDS_LIB logical_power
J 0
(-4950 750);
DISPLAY INVISIBLE (-4950 750);
FORCEPROP 1 LAST PATH I138
J 0
(-4875 750);
DISPLAY 0.872340 (-4875 750);
PAINT AQUA (-4875 750);
DISPLAY INVISIBLE (-4875 750);
FORCEADD Q_RES..2
(-4950 975);
FORCEPROP 1 LAST PART_NUMBER CS31002FB08
J 0
(-4910 850);
DISPLAY 0.510638 (-4910 850);
DISPLAY INVISIBLE (-4910 850);
FORCEPROP 1 LAST VALUE 10K
J 0
(-4905 1050);
DISPLAY 0.510638 (-4905 1050);
FORCEPROP 1 LAST PACK_TYPE 0402LF
J 0
(-4910 800);
DISPLAY 0.510638 (-4910 800);
FORCEPROP 1 LAST TOLERANCE 1%
J 0
(-4905 1000);
DISPLAY 0.510638 (-4905 1000);
FORCEPROP 1 LAST WATTAGE 1/16W
J 0
(-4910 950);
DISPLAY 0.510638 (-4910 950);
FORCEPROP 1 LAST MATERIAL CHIP
J 0
(-4910 900);
DISPLAY 0.510638 (-4910 900);
FORCEPROP 1 LAST $LOCATION R3455
J 0
(-4905 1100);
DISPLAY 0.978723 (-4905 1100);
FORCEPROP 1 LASTPIN (-4950 1075) $PN 1
J 0
(-4945 1037);
DISPLAY 0.787234 (-4945 1037);
PAINT MONO (-4945 1037);
FORCEPROP 1 LASTPIN (-4950 875) $PN 2
J 0
(-4945 885);
DISPLAY 0.787234 (-4945 885);
PAINT MONO (-4945 885);
FORCEPROP 2 LAST CDS_LIB pure_quanta
J 0
(-4950 975);
DISPLAY INVISIBLE (-4950 975);
FORCEPROP 1 LAST PATH I139
J 0
(-4900 1150);
DISPLAY 0.978723 (-4900 1150);
PAINT WHITE (-4900 1150);
DISPLAY INVISIBLE (-4900 1150);
FORCEPROP 0 LAST CDS_LOCATION R3455
J 0
(-4900 1150);
DISPLAY 1.021277 (-4900 1150);
DISPLAY INVISIBLE (-4900 1150);
FORCEPROP 0 LAST $SEC 1
J 0
(-4900 1150);
DISPLAY 0.680851 (-4900 1150);
PAINT MONO (-4900 1150);
DISPLAY INVISIBLE (-4900 1150);
FORCEPROP 0 LAST CDS_SEC 1
J 0
(-4900 1150);
DISPLAY 1.021277 (-4900 1150);
DISPLAY INVISIBLE (-4900 1150);
FORCEADD OFFPAGE..2
(-3425 1250);
FORCEPROP 2 LAST $XR0 143 
J 0
(-3236 1250);
DISPLAY 0.638298 (-3236 1250);
PAINT MONO (-3236 1250);
FORCEPROP 1 LAST COMMENT_BODY TRUE
J 0
(-3470 1155);
DISPLAY 0.872340 (-3470 1155);
PAINT GREEN (-3470 1155);
DISPLAY INVISIBLE (-3470 1155);
FORCEPROP 1 LAST OFFPAGE TRUE
J 0
(-3100 1125);
DISPLAY 0.872340 (-3100 1125);
PAINT AQUA (-3100 1125);
DISPLAY INVISIBLE (-3100 1125);
FORCEPROP 2 LAST CDS_LIB standard
J 0
(-3425 1250);
DISPLAY INVISIBLE (-3425 1250);
FORCEPROP 2 LAST PATH I146
J 0
(-3225 1300);
DISPLAY 1.021277 (-3225 1300);
DISPLAY INVISIBLE (-3225 1300);
FORCEADD Q_CAP..1
(-6075 2175);
FORCEPROP 1 LAST PART_NUMBER CH4104K1B00
J 0
(-6025 2025);
DISPLAY 0.510638 (-6025 2025);
DISPLAY INVISIBLE (-6025 2025);
FORCEPROP 1 LAST MATERIAL X7R
J 0
(-6025 2075);
DISPLAY 0.510638 (-6025 2075);
FORCEPROP 1 LAST TOLERANCE 10%
J 0
(-6025 2125);
DISPLAY 0.510638 (-6025 2125);
FORCEPROP 1 LAST PACK_TYPE 0402
J 0
(-6025 1975);
DISPLAY 0.510638 (-6025 1975);
FORCEPROP 1 LAST VOLTAGE 25V
J 0
(-6025 2175);
DISPLAY 0.510638 (-6025 2175);
FORCEPROP 1 LAST VALUE 0.1UF
J 0
(-6025 2225);
DISPLAY 0.510638 (-6025 2225);
FORCEPROP 1 LAST $LOCATION C1957
J 0
(-6025 2275);
DISPLAY 0.787234 (-6025 2275);
FORCEPROP 1 LASTPIN (-6075 2275) $PN 1
J 0
(-6065 2255);
DISPLAY 0.787234 (-6065 2255);
FORCEPROP 1 LASTPIN (-6075 2075) $PN 2
J 0
(-6065 2055);
DISPLAY 0.787234 (-6065 2055);
FORCEPROP 2 LAST CDS_LIB pure_quanta
J 2
(-6075 2175);
PAINT MONO (-6075 2175);
DISPLAY INVISIBLE (-6075 2175);
FORCEPROP 1 LAST PATH I148
J 0
(-6025 2325);
DISPLAY 0.978723 (-6025 2325);
PAINT WHITE (-6025 2325);
DISPLAY INVISIBLE (-6025 2325);
FORCEPROP 2 LAST CDS_LOCATION C1957
J 0
(-6025 2375);
DISPLAY 1.021277 (-6025 2375);
DISPLAY INVISIBLE (-6025 2375);
FORCEPROP 2 LAST $SEC 1
J 0
(-6025 2375);
DISPLAY 0.680851 (-6025 2375);
PAINT MONO (-6025 2375);
DISPLAY INVISIBLE (-6025 2375);
FORCEPROP 2 LAST CDS_SEC 1
J 0
(-6025 2375);
DISPLAY 1.021277 (-6025 2375);
DISPLAY INVISIBLE (-6025 2375);
FORCEADD UNIVERSAL_GND..1
(-6075 1950);
FORCEPROP 3 LASTPIN (-6075 2000) SIG_NAME GND\g
J 0
(-6065 2010);
DISPLAY 0.659574 (-6065 2010);
PAINT MONO (-6065 2010);
DISPLAY INVISIBLE (-6065 2010);
FORCEPROP 1 LAST HDL_POWER GND
J 1
(-6050 1875);
DISPLAY 0.872340 (-6050 1875);
PAINT GREEN (-6050 1875);
DISPLAY INVISIBLE (-6050 1875);
FORCEPROP 2 LAST CDS_LIB logical_power
J 0
(-6075 1950);
PAINT MONO (-6075 1950);
DISPLAY INVISIBLE (-6075 1950);
FORCEPROP 1 LAST PATH I149
J 0
(-6000 1950);
DISPLAY 0.872340 (-6000 1950);
PAINT AQUA (-6000 1950);
DISPLAY INVISIBLE (-6000 1950);
FORCEADD 74LVC2G17GW..1
(-6250 1575);
FORCEPROP 1 LAST PART_NUMBER AL2G0017005
J 0
(-6800 1175);
DISPLAY 0.723404 (-6800 1175);
PAINT GREEN (-6800 1175);
DISPLAY INVISIBLE (-6800 1175);
FORCEPROP 1 LAST MATERIAL IC
J 0
(-6800 1125);
DISPLAY 0.723404 (-6800 1125);
PAINT GREEN (-6800 1125);
FORCEPROP 2 LAST PART_TYPE SMLF
J 0
(-6800 1275);
DISPLAY 1.021277 (-6800 1275);
FORCEPROP 2 LAST VALUE 74LVC2G17GW
J 0
(-6800 1225);
DISPLAY 1.021277 (-6800 1225);
FORCEPROP 1 LAST $LOCATION U252
J 0
(-6023 1335);
DISPLAY 0.723404 (-6023 1335);
PAINT GREEN (-6023 1335);
FORCEPROP 0 LASTPIN (-6625 1700) $PN 1
J 2
(-6635 1710);
DISPLAY 0.680851 (-6635 1710);
PAINT MONO (-6635 1710);
FORCEPROP 0 LASTPIN (-6625 1450) $PN 3
J 2
(-6635 1460);
DISPLAY 0.680851 (-6635 1460);
PAINT MONO (-6635 1460);
FORCEPROP 0 LASTPIN (-5875 1700) $PN 6
J 0
(-5865 1710);
DISPLAY 0.680851 (-5865 1710);
PAINT MONO (-5865 1710);
FORCEPROP 0 LASTPIN (-5875 1450) $PN 4
J 0
(-5865 1460);
DISPLAY 0.680851 (-5865 1460);
PAINT MONO (-5865 1460);
FORCEPROP 0 LASTPIN (-6225 1150) $PN 2
R 1
J 2
(-6235 1140);
DISPLAY 0.680851 (-6235 1140);
PAINT MONO (-6235 1140);
FORCEPROP 0 LASTPIN (-6225 2000) $PN 5
R 1
J 0
(-6235 2010);
DISPLAY 0.680851 (-6235 2010);
PAINT MONO (-6235 2010);
FORCEPROP 1 LAST PATH I153
J 0
(-6025 1300);
DISPLAY 0.723404 (-6025 1300);
PAINT GREEN (-6025 1300);
DISPLAY INVISIBLE (-6025 1300);
FORCEPROP 1 LAST CDS_LMAN_SYM_OUTLINE -225,275,225,-275
J 0
(-6250 1575);
DISPLAY 0.468085 (-6250 1575);
PAINT GREEN (-6250 1575);
DISPLAY INVISIBLE (-6250 1575);
FORCEPROP 1 LAST NEEDS_NO_SIZE TRUE
J 0
(-6025 1574);
DISPLAY 0.468085 (-6025 1574);
PAINT GREEN (-6025 1574);
DISPLAY INVISIBLE (-6025 1574);
FORCEPROP 2 LAST CDS_LIB pure_quanta
J 0
(-6250 1575);
DISPLAY INVISIBLE (-6250 1575);
FORCEPROP 0 LAST CDS_LOCATION U252
J 0
(-6000 1375);
DISPLAY 1.021277 (-6000 1375);
DISPLAY INVISIBLE (-6000 1375);
FORCEPROP 0 LAST $SEC 1
J 0
(-6000 1375);
DISPLAY 0.680851 (-6000 1375);
PAINT MONO (-6000 1375);
DISPLAY INVISIBLE (-6000 1375);
FORCEPROP 0 LAST CDS_SEC 1
J 0
(-6000 1375);
DISPLAY 1.021277 (-6000 1375);
DISPLAY INVISIBLE (-6000 1375);
FORCEADD UNIVERSAL_POWER..1
(-6075 2500);
FORCEPROP 3 LASTPIN (-6075 2450) SIG_NAME P3V3_AUX\g
J 0
(-6065 2460);
DISPLAY 0.659574 (-6065 2460);
PAINT MONO (-6065 2460);
DISPLAY INVISIBLE (-6065 2460);
FORCEPROP 1 LAST HDL_POWER P3V3_AUX
J 1
(-6075 2550);
DISPLAY 0.872340 (-6075 2550);
PAINT GREEN (-6075 2550);
FORCEPROP 2 LAST CDS_LIB logical_power
J 0
(-6075 2500);
PAINT MONO (-6075 2500);
DISPLAY INVISIBLE (-6075 2500);
FORCEPROP 1 LAST PATH I154
J 0
(-6025 2525);
DISPLAY 0.872340 (-6025 2525);
PAINT AQUA (-6025 2525);
DISPLAY INVISIBLE (-6025 2525);
FORCEADD UNIVERSAL_GND..1
(-7575 2625);
FORCEPROP 3 LASTPIN (-7575 2675) SIG_NAME GND\g
J 0
(-7565 2685);
DISPLAY 0.659574 (-7565 2685);
PAINT MONO (-7565 2685);
DISPLAY INVISIBLE (-7565 2685);
FORCEPROP 1 LAST HDL_POWER GND
J 1
(-7550 2550);
DISPLAY 0.872340 (-7550 2550);
PAINT GREEN (-7550 2550);
DISPLAY INVISIBLE (-7550 2550);
FORCEPROP 2 LAST CDS_LIB logical_power
J 0
(-7575 2625);
DISPLAY INVISIBLE (-7575 2625);
FORCEPROP 1 LAST PATH I16
J 0
(-7500 2625);
DISPLAY 0.872340 (-7500 2625);
PAINT AQUA (-7500 2625);
DISPLAY INVISIBLE (-7500 2625);
FORCEADD OFFPAGE..2
(-3475 4125);
FORCEPROP 2 LAST $XR0 141 
J 0
(-3286 4125);
DISPLAY 0.638298 (-3286 4125);
PAINT MONO (-3286 4125);
FORCEPROP 2 LAST PATH I161
J 0
(-3275 4175);
DISPLAY 1.021277 (-3275 4175);
DISPLAY INVISIBLE (-3275 4175);
FORCEPROP 2 LAST CDS_LIB standard
J 0
(-3475 4125);
DISPLAY INVISIBLE (-3475 4125);
FORCEPROP 1 LAST OFFPAGE TRUE
J 0
(-3150 4000);
DISPLAY 0.872340 (-3150 4000);
PAINT AQUA (-3150 4000);
DISPLAY INVISIBLE (-3150 4000);
FORCEPROP 1 LAST COMMENT_BODY TRUE
J 0
(-3520 4030);
DISPLAY 0.872340 (-3520 4030);
PAINT GREEN (-3520 4030);
DISPLAY INVISIBLE (-3520 4030);
FORCEADD UNIVERSAL_POWER..1
(-5000 4675);
FORCEPROP 3 LASTPIN (-5000 4625) SIG_NAME P3V3_AUX\g
J 0
(-4990 4635);
DISPLAY 0.659574 (-4990 4635);
PAINT MONO (-4990 4635);
DISPLAY INVISIBLE (-4990 4635);
FORCEPROP 1 LAST HDL_POWER P3V3_AUX
J 1
(-5000 4725);
DISPLAY 0.872340 (-5000 4725);
PAINT GREEN (-5000 4725);
FORCEPROP 1 LAST PATH I163
J 0
(-4950 4700);
DISPLAY 0.872340 (-4950 4700);
PAINT AQUA (-4950 4700);
DISPLAY INVISIBLE (-4950 4700);
FORCEPROP 2 LAST CDS_LIB logical_power
J 0
(-5000 4675);
PAINT MONO (-5000 4675);
DISPLAY INVISIBLE (-5000 4675);
FORCEADD Q_RES..2
(-5000 4425);
FORCEPROP 1 LAST PART_NUMBER CS41002FB09
J 0
(-4960 4300);
DISPLAY 0.510638 (-4960 4300);
DISPLAY INVISIBLE (-4960 4300);
FORCEPROP 1 LAST MATERIAL EMPTY
J 0
(-4960 4350);
DISPLAY 0.510638 (-4960 4350);
PAINT RED (-4960 4350);
FORCEPROP 1 LAST VALUE 100K
J 0
(-4955 4500);
DISPLAY 0.510638 (-4955 4500);
FORCEPROP 1 LAST TOLERANCE 1%
J 0
(-4955 4450);
DISPLAY 0.510638 (-4955 4450);
FORCEPROP 1 LAST WATTAGE 1/16W
J 0
(-4960 4400);
DISPLAY 0.510638 (-4960 4400);
FORCEPROP 1 LAST PACK_TYPE 0402LF
J 0
(-4960 4250);
DISPLAY 0.510638 (-4960 4250);
FORCEPROP 1 LAST $LOCATION R3453
J 0
(-4955 4550);
DISPLAY 0.978723 (-4955 4550);
FORCEPROP 1 LASTPIN (-5000 4525) $PN 1
J 0
(-4995 4487);
DISPLAY 0.787234 (-4995 4487);
PAINT MONO (-4995 4487);
FORCEPROP 1 LASTPIN (-5000 4325) $PN 2
J 0
(-4995 4335);
DISPLAY 0.787234 (-4995 4335);
PAINT MONO (-4995 4335);
FORCEPROP 1 LAST PATH I164
J 0
(-4950 4600);
DISPLAY 0.978723 (-4950 4600);
PAINT WHITE (-4950 4600);
DISPLAY INVISIBLE (-4950 4600);
FORCEPROP 2 LAST CDS_LIB pure_quanta
J 0
(-5000 4425);
DISPLAY INVISIBLE (-5000 4425);
FORCEPROP 0 LAST CDS_LOCATION R3453
J 0
(-4950 4600);
DISPLAY 1.021277 (-4950 4600);
DISPLAY INVISIBLE (-4950 4600);
FORCEPROP 0 LAST $SEC 1
J 0
(-4950 4600);
DISPLAY 0.680851 (-4950 4600);
PAINT MONO (-4950 4600);
DISPLAY INVISIBLE (-4950 4600);
FORCEPROP 0 LAST CDS_SEC 1
J 0
(-4950 4600);
DISPLAY 1.021277 (-4950 4600);
DISPLAY INVISIBLE (-4950 4600);
FORCEADD Q_RES..2
(-4975 3825);
FORCEPROP 1 LAST PART_NUMBER CS21002FB06
J 0
(-4935 3700);
DISPLAY 0.638298 (-4935 3700);
DISPLAY INVISIBLE (-4935 3700);
FORCEPROP 1 LAST WATTAGE 1/16W
J 0
(-4935 3800);
DISPLAY 0.638298 (-4935 3800);
FORCEPROP 1 LAST VALUE 1K
J 0
(-4930 3900);
DISPLAY 0.638298 (-4930 3900);
FORCEPROP 1 LAST TOLERANCE 1%
J 0
(-4930 3850);
DISPLAY 0.638298 (-4930 3850);
FORCEPROP 1 LAST MATERIAL CHIP
J 0
(-4935 3750);
DISPLAY 0.638298 (-4935 3750);
FORCEPROP 1 LAST PACK_TYPE 0402LF
J 0
(-4935 3650);
DISPLAY 0.638298 (-4935 3650);
FORCEPROP 1 LAST $LOCATION R3454
J 0
(-4930 3950);
DISPLAY 0.978723 (-4930 3950);
FORCEPROP 1 LASTPIN (-4975 3925) $PN 1
J 0
(-4970 3887);
DISPLAY 0.787234 (-4970 3887);
PAINT MONO (-4970 3887);
FORCEPROP 1 LASTPIN (-4975 3725) $PN 2
J 0
(-4970 3735);
DISPLAY 0.787234 (-4970 3735);
PAINT MONO (-4970 3735);
FORCEPROP 1 LAST PATH I165
J 0
(-4925 4000);
DISPLAY 0.978723 (-4925 4000);
PAINT WHITE (-4925 4000);
DISPLAY INVISIBLE (-4925 4000);
FORCEPROP 2 LAST CDS_LIB pure_quanta
J 0
(-4975 3825);
DISPLAY INVISIBLE (-4975 3825);
FORCEPROP 0 LAST CDS_LOCATION R3454
J 0
(-4925 4000);
DISPLAY 1.021277 (-4925 4000);
DISPLAY INVISIBLE (-4925 4000);
FORCEPROP 0 LAST $SEC 1
J 0
(-4925 4000);
DISPLAY 0.680851 (-4925 4000);
PAINT MONO (-4925 4000);
DISPLAY INVISIBLE (-4925 4000);
FORCEPROP 0 LAST CDS_SEC 1
J 0
(-4925 4000);
DISPLAY 1.021277 (-4925 4000);
DISPLAY INVISIBLE (-4925 4000);
FORCEADD UNIVERSAL_GND..1
(-4975 3625);
FORCEPROP 3 LASTPIN (-4975 3675) SIG_NAME GND\g
J 0
(-4965 3685);
DISPLAY 0.659574 (-4965 3685);
PAINT MONO (-4965 3685);
DISPLAY INVISIBLE (-4965 3685);
FORCEPROP 1 LAST PATH I166
J 0
(-4900 3625);
DISPLAY 0.872340 (-4900 3625);
PAINT AQUA (-4900 3625);
DISPLAY INVISIBLE (-4900 3625);
FORCEPROP 2 LAST CDS_LIB logical_power
J 0
(-4975 3625);
DISPLAY INVISIBLE (-4975 3625);
FORCEPROP 1 LAST HDL_POWER GND
J 1
(-4950 3550);
DISPLAY 0.872340 (-4950 3550);
PAINT GREEN (-4950 3550);
DISPLAY INVISIBLE (-4950 3550);
FORCEADD UNIVERSAL_POWER..1
(-7600 4650);
FORCEPROP 3 LASTPIN (-7600 4600) SIG_NAME P3V3_AUX\g
J 0
(-7590 4610);
DISPLAY 0.659574 (-7590 4610);
PAINT MONO (-7590 4610);
DISPLAY INVISIBLE (-7590 4610);
FORCEPROP 1 LAST HDL_POWER P3V3_AUX
J 1
(-7600 4700);
DISPLAY 0.872340 (-7600 4700);
PAINT GREEN (-7600 4700);
FORCEPROP 2 LAST CDS_LIB logical_power
J 0
(-7600 4650);
PAINT MONO (-7600 4650);
DISPLAY INVISIBLE (-7600 4650);
FORCEPROP 1 LAST PATH I167
J 0
(-7550 4675);
DISPLAY 0.872340 (-7550 4675);
PAINT AQUA (-7550 4675);
DISPLAY INVISIBLE (-7550 4675);
FORCEADD Q_RES..2
(-7600 4400);
FORCEPROP 1 LAST PART_NUMBER CS24702JB10
J 0
(-7560 4225);
DISPLAY 0.638298 (-7560 4225);
DISPLAY INVISIBLE (-7560 4225);
FORCEPROP 1 LAST TOLERANCE 5%
J 0
(-7555 4425);
DISPLAY 0.638298 (-7555 4425);
FORCEPROP 1 LAST WATTAGE 1/16W
J 0
(-7560 4375);
DISPLAY 0.638298 (-7560 4375);
FORCEPROP 1 LAST PACK_TYPE 0402LF
J 0
(-7560 4275);
DISPLAY 0.638298 (-7560 4275);
FORCEPROP 1 LAST MATERIAL EMPTY
J 0
(-7560 4325);
DISPLAY 0.638298 (-7560 4325);
PAINT RED (-7560 4325);
FORCEPROP 1 LAST VALUE 4.7K
J 0
(-7555 4475);
DISPLAY 0.638298 (-7555 4475);
FORCEPROP 1 LAST $LOCATION R3448
J 0
(-7555 4525);
DISPLAY 0.978723 (-7555 4525);
FORCEPROP 1 LASTPIN (-7600 4500) $PN 1
J 0
(-7595 4462);
DISPLAY 0.787234 (-7595 4462);
PAINT MONO (-7595 4462);
FORCEPROP 1 LASTPIN (-7600 4300) $PN 2
J 0
(-7595 4310);
DISPLAY 0.787234 (-7595 4310);
PAINT MONO (-7595 4310);
FORCEPROP 2 LAST CDS_LIB pure_quanta
J 0
(-7600 4400);
DISPLAY INVISIBLE (-7600 4400);
FORCEPROP 1 LAST PATH I168
J 0
(-7550 4575);
DISPLAY 0.978723 (-7550 4575);
PAINT WHITE (-7550 4575);
DISPLAY INVISIBLE (-7550 4575);
FORCEPROP 0 LAST CDS_LOCATION R3448
J 0
(-7550 4575);
DISPLAY 1.021277 (-7550 4575);
DISPLAY INVISIBLE (-7550 4575);
FORCEPROP 0 LAST $SEC 1
J 0
(-7550 4575);
DISPLAY 0.680851 (-7550 4575);
PAINT MONO (-7550 4575);
DISPLAY INVISIBLE (-7550 4575);
FORCEPROP 0 LAST CDS_SEC 1
J 0
(-7550 4575);
DISPLAY 1.021277 (-7550 4575);
DISPLAY INVISIBLE (-7550 4575);
FORCEADD OFFPAGE..4
R 2
(-7850 4125);
FORCEPROP 2 LAST $XR0 213 
J 0
(-8102 4125);
DISPLAY 0.638298 (-8102 4125);
PAINT MONO (-8102 4125);
FORCEPROP 2 LAST CDS_LIB standard
J 0
(-7850 4125);
DISPLAY INVISIBLE (-7850 4125);
FORCEPROP 1 LAST COMMENT_BODY TRUE
J 2
(-7825 4025);
DISPLAY 0.872340 (-7825 4025);
PAINT GREEN (-7825 4025);
DISPLAY INVISIBLE (-7825 4025);
FORCEPROP 1 LAST OFFPAGE TRUE
J 2
(-8175 4000);
DISPLAY 0.872340 (-8175 4000);
PAINT GREEN (-8175 4000);
DISPLAY INVISIBLE (-8175 4000);
FORCEPROP 2 LAST PATH I169
J 0
(-8125 4175);
DISPLAY 1.021277 (-8125 4175);
DISPLAY INVISIBLE (-8125 4175);
FORCEADD Q_RES..2
(-7575 3925);
FORCEPROP 1 LAST PART_NUMBER CS41002FB09
J 0
(-7535 3800);
DISPLAY 0.510638 (-7535 3800);
DISPLAY INVISIBLE (-7535 3800);
FORCEPROP 1 LAST VALUE 100K
J 0
(-7530 4000);
DISPLAY 0.510638 (-7530 4000);
FORCEPROP 1 LAST MATERIAL CHIP
J 0
(-7535 3850);
DISPLAY 0.510638 (-7535 3850);
FORCEPROP 1 LAST TOLERANCE 1%
J 0
(-7530 3950);
DISPLAY 0.510638 (-7530 3950);
FORCEPROP 1 LAST PACK_TYPE 0402LF
J 0
(-7535 3750);
DISPLAY 0.510638 (-7535 3750);
FORCEPROP 1 LAST WATTAGE 1/16W
J 0
(-7535 3900);
DISPLAY 0.510638 (-7535 3900);
FORCEPROP 1 LAST $LOCATION R3449
J 0
(-7530 4050);
DISPLAY 0.978723 (-7530 4050);
FORCEPROP 1 LASTPIN (-7575 4025) $PN 1
J 0
(-7570 3987);
DISPLAY 0.787234 (-7570 3987);
PAINT MONO (-7570 3987);
FORCEPROP 1 LASTPIN (-7575 3825) $PN 2
J 0
(-7570 3835);
DISPLAY 0.787234 (-7570 3835);
PAINT MONO (-7570 3835);
FORCEPROP 1 LAST PATH I170
J 0
(-7525 4100);
DISPLAY 0.978723 (-7525 4100);
PAINT WHITE (-7525 4100);
DISPLAY INVISIBLE (-7525 4100);
FORCEPROP 2 LAST CDS_LIB pure_quanta
J 0
(-7575 3925);
DISPLAY INVISIBLE (-7575 3925);
FORCEPROP 0 LAST CDS_LOCATION R3449
J 0
(-7525 4100);
DISPLAY 1.021277 (-7525 4100);
DISPLAY INVISIBLE (-7525 4100);
FORCEPROP 0 LAST $SEC 1
J 0
(-7525 4100);
DISPLAY 0.680851 (-7525 4100);
PAINT MONO (-7525 4100);
DISPLAY INVISIBLE (-7525 4100);
FORCEPROP 0 LAST CDS_SEC 1
J 0
(-7525 4100);
DISPLAY 1.021277 (-7525 4100);
DISPLAY INVISIBLE (-7525 4100);
FORCEADD UNIVERSAL_GND..1
(-7575 3725);
FORCEPROP 3 LASTPIN (-7575 3775) SIG_NAME GND\g
J 0
(-7565 3785);
DISPLAY 0.659574 (-7565 3785);
PAINT MONO (-7565 3785);
DISPLAY INVISIBLE (-7565 3785);
FORCEPROP 1 LAST PATH I171
J 0
(-7500 3725);
DISPLAY 0.872340 (-7500 3725);
PAINT AQUA (-7500 3725);
DISPLAY INVISIBLE (-7500 3725);
FORCEPROP 1 LAST HDL_POWER GND
J 1
(-7550 3650);
DISPLAY 0.872340 (-7550 3650);
PAINT GREEN (-7550 3650);
DISPLAY INVISIBLE (-7550 3650);
FORCEPROP 2 LAST CDS_LIB logical_power
J 0
(-7575 3725);
DISPLAY INVISIBLE (-7575 3725);
FORCEADD OFFPAGE..4
R 2
(-8300 1700);
FORCEPROP 2 LAST $XR0 223 
J 0
(-8552 1700);
DISPLAY 0.638298 (-8552 1700);
PAINT MONO (-8552 1700);
FORCEPROP 1 LAST OFFPAGE TRUE
J 2
(-8625 1575);
DISPLAY 0.872340 (-8625 1575);
PAINT GREEN (-8625 1575);
DISPLAY INVISIBLE (-8625 1575);
FORCEPROP 1 LAST COMMENT_BODY TRUE
J 2
(-8275 1600);
DISPLAY 0.872340 (-8275 1600);
PAINT GREEN (-8275 1600);
DISPLAY INVISIBLE (-8275 1600);
FORCEPROP 2 LAST CDS_LIB standard
J 0
(-8300 1700);
DISPLAY INVISIBLE (-8300 1700);
FORCEPROP 2 LAST PATH I172
J 0
(-8550 1750);
DISPLAY 1.021277 (-8550 1750);
DISPLAY INVISIBLE (-8550 1750);
FORCEADD 74LVC2G17GW..1
(-6325 -275);
FORCEPROP 1 LAST PART_NUMBER AL2G0017005
J 0
(-6900 -675);
DISPLAY 0.723404 (-6900 -675);
PAINT GREEN (-6900 -675);
DISPLAY INVISIBLE (-6900 -675);
FORCEPROP 1 LAST MATERIAL IC
J 0
(-6900 -725);
DISPLAY 0.723404 (-6900 -725);
PAINT GREEN (-6900 -725);
FORCEPROP 2 LAST VALUE 74LVC2G17GW
J 0
(-6900 -625);
DISPLAY 1.021277 (-6900 -625);
FORCEPROP 2 LAST PART_TYPE SMLF
J 0
(-6900 -575);
DISPLAY 1.021277 (-6900 -575);
FORCEPROP 1 LAST $LOCATION U256
J 0
(-6098 -515);
DISPLAY 0.723404 (-6098 -515);
PAINT GREEN (-6098 -515);
FORCEPROP 0 LASTPIN (-6700 -150) $PN 1
J 2
(-6710 -140);
DISPLAY 0.680851 (-6710 -140);
PAINT MONO (-6710 -140);
FORCEPROP 0 LASTPIN (-6700 -400) $PN 3
J 2
(-6710 -390);
DISPLAY 0.680851 (-6710 -390);
PAINT MONO (-6710 -390);
FORCEPROP 0 LASTPIN (-5950 -150) $PN 6
J 0
(-5940 -140);
DISPLAY 0.680851 (-5940 -140);
PAINT MONO (-5940 -140);
FORCEPROP 0 LASTPIN (-5950 -400) $PN 4
J 0
(-5940 -390);
DISPLAY 0.680851 (-5940 -390);
PAINT MONO (-5940 -390);
FORCEPROP 0 LASTPIN (-6300 -700) $PN 2
R 1
J 2
(-6310 -710);
DISPLAY 0.680851 (-6310 -710);
PAINT MONO (-6310 -710);
FORCEPROP 0 LASTPIN (-6300 150) $PN 5
R 1
J 0
(-6310 160);
DISPLAY 0.680851 (-6310 160);
PAINT MONO (-6310 160);
FORCEPROP 1 LAST PATH I173
J 0
(-6100 -550);
DISPLAY 0.723404 (-6100 -550);
PAINT GREEN (-6100 -550);
DISPLAY INVISIBLE (-6100 -550);
FORCEPROP 1 LAST CDS_LMAN_SYM_OUTLINE -225,275,225,-275
J 0
(-6325 -275);
DISPLAY 0.468085 (-6325 -275);
PAINT GREEN (-6325 -275);
DISPLAY INVISIBLE (-6325 -275);
FORCEPROP 1 LAST NEEDS_NO_SIZE TRUE
J 0
(-6100 -276);
DISPLAY 0.468085 (-6100 -276);
PAINT GREEN (-6100 -276);
DISPLAY INVISIBLE (-6100 -276);
FORCEPROP 2 LAST CDS_LIB pure_quanta
J 0
(-6325 -275);
DISPLAY INVISIBLE (-6325 -275);
FORCEPROP 0 LAST CDS_LOCATION U256
J 0
(-6075 -475);
DISPLAY 1.021277 (-6075 -475);
DISPLAY INVISIBLE (-6075 -475);
FORCEPROP 0 LAST $SEC 1
J 0
(-6075 -475);
DISPLAY 0.680851 (-6075 -475);
PAINT MONO (-6075 -475);
DISPLAY INVISIBLE (-6075 -475);
FORCEPROP 0 LAST CDS_SEC 1
J 0
(-6075 -475);
DISPLAY 1.021277 (-6075 -475);
DISPLAY INVISIBLE (-6075 -475);
FORCEADD UNIVERSAL_POWER..1
(-6175 625);
FORCEPROP 3 LASTPIN (-6175 575) SIG_NAME P3V3_AUX\g
J 0
(-6165 585);
DISPLAY 0.659574 (-6165 585);
PAINT MONO (-6165 585);
DISPLAY INVISIBLE (-6165 585);
FORCEPROP 1 LAST HDL_POWER P3V3_AUX
J 1
(-6175 675);
DISPLAY 0.872340 (-6175 675);
PAINT GREEN (-6175 675);
FORCEPROP 2 LAST CDS_LIB logical_power
J 0
(-6175 625);
PAINT MONO (-6175 625);
DISPLAY INVISIBLE (-6175 625);
FORCEPROP 1 LAST PATH I174
J 0
(-6125 650);
DISPLAY 0.872340 (-6125 650);
PAINT AQUA (-6125 650);
DISPLAY INVISIBLE (-6125 650);
FORCEADD Q_CAP..1
(-6175 300);
FORCEPROP 1 LAST PART_NUMBER CH4104K1B00
J 0
(-6125 150);
DISPLAY 0.510638 (-6125 150);
DISPLAY INVISIBLE (-6125 150);
FORCEPROP 1 LAST VALUE 0.1UF
J 0
(-6125 350);
DISPLAY 0.510638 (-6125 350);
FORCEPROP 1 LAST MATERIAL X7R
J 0
(-6125 200);
DISPLAY 0.510638 (-6125 200);
FORCEPROP 1 LAST TOLERANCE 10%
J 0
(-6125 250);
DISPLAY 0.510638 (-6125 250);
FORCEPROP 1 LAST VOLTAGE 25V
J 0
(-6125 300);
DISPLAY 0.510638 (-6125 300);
FORCEPROP 1 LAST PACK_TYPE 0402
J 0
(-6125 100);
DISPLAY 0.510638 (-6125 100);
FORCEPROP 1 LAST $LOCATION C1977
J 0
(-6125 400);
DISPLAY 0.787234 (-6125 400);
FORCEPROP 1 LASTPIN (-6175 400) $PN 1
J 0
(-6165 380);
DISPLAY 0.787234 (-6165 380);
FORCEPROP 1 LASTPIN (-6175 200) $PN 2
J 0
(-6165 180);
DISPLAY 0.787234 (-6165 180);
FORCEPROP 2 LAST CDS_LIB pure_quanta
J 2
(-6175 300);
PAINT MONO (-6175 300);
DISPLAY INVISIBLE (-6175 300);
FORCEPROP 1 LAST PATH I175
J 0
(-6125 450);
DISPLAY 0.978723 (-6125 450);
PAINT WHITE (-6125 450);
DISPLAY INVISIBLE (-6125 450);
FORCEPROP 2 LAST CDS_LOCATION C1977
J 0
(-6125 500);
DISPLAY 1.021277 (-6125 500);
DISPLAY INVISIBLE (-6125 500);
FORCEPROP 2 LAST $SEC 1
J 0
(-6125 500);
DISPLAY 0.680851 (-6125 500);
PAINT MONO (-6125 500);
DISPLAY INVISIBLE (-6125 500);
FORCEPROP 2 LAST CDS_SEC 1
J 0
(-6125 500);
DISPLAY 1.021277 (-6125 500);
DISPLAY INVISIBLE (-6125 500);
FORCEADD UNIVERSAL_GND..1
(-6175 75);
FORCEPROP 3 LASTPIN (-6175 125) SIG_NAME GND\g
J 0
(-6165 135);
DISPLAY 0.659574 (-6165 135);
PAINT MONO (-6165 135);
DISPLAY INVISIBLE (-6165 135);
FORCEPROP 1 LAST HDL_POWER GND
J 1
(-6150 0);
DISPLAY 0.872340 (-6150 0);
PAINT GREEN (-6150 0);
DISPLAY INVISIBLE (-6150 0);
FORCEPROP 2 LAST CDS_LIB logical_power
J 0
(-6175 75);
PAINT MONO (-6175 75);
DISPLAY INVISIBLE (-6175 75);
FORCEPROP 1 LAST PATH I176
J 0
(-6100 75);
DISPLAY 0.872340 (-6100 75);
PAINT AQUA (-6100 75);
DISPLAY INVISIBLE (-6100 75);
FORCEADD UNIVERSAL_GND..1
(-6300 -850);
FORCEPROP 3 LASTPIN (-6300 -800) SIG_NAME GND\g
J 0
(-6290 -790);
DISPLAY 0.659574 (-6290 -790);
PAINT MONO (-6290 -790);
DISPLAY INVISIBLE (-6290 -790);
FORCEPROP 1 LAST PATH I177
J 0
(-6225 -850);
DISPLAY 0.872340 (-6225 -850);
PAINT AQUA (-6225 -850);
DISPLAY INVISIBLE (-6225 -850);
FORCEPROP 2 LAST CDS_LIB logical_power
J 0
(-6300 -850);
DISPLAY INVISIBLE (-6300 -850);
FORCEPROP 1 LAST HDL_POWER GND
J 1
(-6275 -925);
DISPLAY 0.872340 (-6275 -925);
PAINT GREEN (-6275 -925);
DISPLAY INVISIBLE (-6275 -925);
FORCEADD UNIVERSAL_GND..1
(-4950 1400);
FORCEPROP 3 LASTPIN (-4950 1450) SIG_NAME GND\g
J 0
(-4940 1460);
DISPLAY 0.659574 (-4940 1460);
PAINT MONO (-4940 1460);
DISPLAY INVISIBLE (-4940 1460);
FORCEPROP 1 LAST PATH I178
J 0
(-4875 1400);
DISPLAY 0.872340 (-4875 1400);
PAINT AQUA (-4875 1400);
DISPLAY INVISIBLE (-4875 1400);
FORCEPROP 2 LAST CDS_LIB logical_power
J 0
(-4950 1400);
DISPLAY INVISIBLE (-4950 1400);
FORCEPROP 1 LAST HDL_POWER GND
J 1
(-4925 1325);
DISPLAY 0.872340 (-4925 1325);
PAINT GREEN (-4925 1325);
DISPLAY INVISIBLE (-4925 1325);
FORCEADD OFFPAGE..2
(-3425 1900);
FORCEPROP 2 LAST $XR0 143 
J 0
(-3236 1900);
DISPLAY 0.638298 (-3236 1900);
PAINT MONO (-3236 1900);
FORCEPROP 2 LAST PATH I179
J 0
(-3225 1950);
DISPLAY 1.021277 (-3225 1950);
DISPLAY INVISIBLE (-3225 1950);
FORCEPROP 2 LAST CDS_LIB standard
J 0
(-3425 1900);
DISPLAY INVISIBLE (-3425 1900);
FORCEPROP 1 LAST OFFPAGE TRUE
J 0
(-3100 1775);
DISPLAY 0.872340 (-3100 1775);
PAINT AQUA (-3100 1775);
DISPLAY INVISIBLE (-3100 1775);
FORCEPROP 1 LAST COMMENT_BODY TRUE
J 0
(-3470 1805);
DISPLAY 0.872340 (-3470 1805);
PAINT GREEN (-3470 1805);
DISPLAY INVISIBLE (-3470 1805);
FORCEADD OFFPAGE..4
R 2
(-7800 3075);
FORCEPROP 2 LAST $XR0 213 
J 0
(-8052 3075);
DISPLAY 0.638298 (-8052 3075);
PAINT MONO (-8052 3075);
FORCEPROP 2 LAST PATH I18
J 0
(-8050 3125);
DISPLAY 1.021277 (-8050 3125);
DISPLAY INVISIBLE (-8050 3125);
FORCEPROP 2 LAST CDS_LIB standard
J 0
(-7800 3075);
DISPLAY INVISIBLE (-7800 3075);
FORCEPROP 1 LAST COMMENT_BODY TRUE
J 2
(-7775 2975);
DISPLAY 0.872340 (-7775 2975);
PAINT GREEN (-7775 2975);
DISPLAY INVISIBLE (-7775 2975);
FORCEPROP 1 LAST OFFPAGE TRUE
J 2
(-8125 2950);
DISPLAY 0.872340 (-8125 2950);
PAINT GREEN (-8125 2950);
DISPLAY INVISIBLE (-8125 2950);
FORCEADD Q_RES..2
(-4950 1625);
FORCEPROP 1 LAST PART_NUMBER CS31002FB08
J 0
(-4910 1500);
DISPLAY 0.510638 (-4910 1500);
DISPLAY INVISIBLE (-4910 1500);
FORCEPROP 1 LAST VALUE 10K
J 0
(-4905 1700);
DISPLAY 0.510638 (-4905 1700);
FORCEPROP 1 LAST WATTAGE 1/16W
J 0
(-4910 1600);
DISPLAY 0.510638 (-4910 1600);
FORCEPROP 1 LAST PACK_TYPE 0402LF
J 0
(-4910 1450);
DISPLAY 0.510638 (-4910 1450);
FORCEPROP 1 LAST TOLERANCE 1%
J 0
(-4905 1650);
DISPLAY 0.510638 (-4905 1650);
FORCEPROP 1 LAST MATERIAL CHIP
J 0
(-4910 1550);
DISPLAY 0.510638 (-4910 1550);
FORCEPROP 1 LAST $LOCATION R3467
J 0
(-4905 1750);
DISPLAY 0.978723 (-4905 1750);
FORCEPROP 1 LASTPIN (-4950 1725) $PN 1
J 0
(-4945 1687);
DISPLAY 0.787234 (-4945 1687);
PAINT MONO (-4945 1687);
FORCEPROP 1 LASTPIN (-4950 1525) $PN 2
J 0
(-4945 1535);
DISPLAY 0.787234 (-4945 1535);
PAINT MONO (-4945 1535);
FORCEPROP 1 LAST PATH I181
J 0
(-4900 1800);
DISPLAY 0.978723 (-4900 1800);
PAINT WHITE (-4900 1800);
DISPLAY INVISIBLE (-4900 1800);
FORCEPROP 2 LAST CDS_LIB pure_quanta
J 0
(-4950 1625);
DISPLAY INVISIBLE (-4950 1625);
FORCEPROP 0 LAST CDS_LOCATION R3467
J 0
(-4900 1800);
DISPLAY 1.021277 (-4900 1800);
DISPLAY INVISIBLE (-4900 1800);
FORCEPROP 0 LAST $SEC 1
J 0
(-4900 1800);
DISPLAY 0.680851 (-4900 1800);
PAINT MONO (-4900 1800);
DISPLAY INVISIBLE (-4900 1800);
FORCEPROP 0 LAST CDS_SEC 1
J 0
(-4900 1800);
DISPLAY 1.021277 (-4900 1800);
DISPLAY INVISIBLE (-4900 1800);
FORCEADD OFFPAGE..2
(-3425 100);
FORCEPROP 2 LAST $XR0 143 
J 0
(-3236 100);
DISPLAY 0.638298 (-3236 100);
PAINT MONO (-3236 100);
FORCEPROP 2 LAST PATH I182
J 0
(-3225 150);
DISPLAY 1.021277 (-3225 150);
DISPLAY INVISIBLE (-3225 150);
FORCEPROP 2 LAST CDS_LIB standard
J 0
(-3425 100);
DISPLAY INVISIBLE (-3425 100);
FORCEPROP 1 LAST OFFPAGE TRUE
J 0
(-3100 -25);
DISPLAY 0.872340 (-3100 -25);
PAINT AQUA (-3100 -25);
DISPLAY INVISIBLE (-3100 -25);
FORCEPROP 1 LAST COMMENT_BODY TRUE
J 0
(-3470 5);
DISPLAY 0.872340 (-3470 5);
PAINT GREEN (-3470 5);
DISPLAY INVISIBLE (-3470 5);
FORCEADD Q_RES..2
(-4975 -175);
FORCEPROP 1 LAST PART_NUMBER CS31002FB08
J 0
(-4935 -300);
DISPLAY 0.510638 (-4935 -300);
DISPLAY INVISIBLE (-4935 -300);
FORCEPROP 1 LAST MATERIAL CHIP
J 0
(-4935 -250);
DISPLAY 0.510638 (-4935 -250);
FORCEPROP 1 LAST TOLERANCE 1%
J 0
(-4930 -150);
DISPLAY 0.510638 (-4930 -150);
FORCEPROP 1 LAST PACK_TYPE 0402LF
J 0
(-4935 -350);
DISPLAY 0.510638 (-4935 -350);
FORCEPROP 1 LAST VALUE 10K
J 0
(-4930 -100);
DISPLAY 0.510638 (-4930 -100);
FORCEPROP 1 LAST WATTAGE 1/16W
J 0
(-4935 -200);
DISPLAY 0.510638 (-4935 -200);
FORCEPROP 1 LAST $LOCATION R3466
J 0
(-4930 -50);
DISPLAY 0.978723 (-4930 -50);
FORCEPROP 1 LASTPIN (-4975 -75) $PN 1
J 0
(-4970 -113);
DISPLAY 0.787234 (-4970 -113);
PAINT MONO (-4970 -113);
FORCEPROP 1 LASTPIN (-4975 -275) $PN 2
J 0
(-4970 -265);
DISPLAY 0.787234 (-4970 -265);
PAINT MONO (-4970 -265);
FORCEPROP 2 LAST CDS_LIB pure_quanta
J 0
(-4975 -175);
DISPLAY INVISIBLE (-4975 -175);
FORCEPROP 1 LAST PATH I184
J 0
(-4925 0);
DISPLAY 0.978723 (-4925 0);
PAINT WHITE (-4925 0);
DISPLAY INVISIBLE (-4925 0);
FORCEPROP 0 LAST CDS_LOCATION R3466
J 0
(-4925 0);
DISPLAY 1.021277 (-4925 0);
DISPLAY INVISIBLE (-4925 0);
FORCEPROP 0 LAST $SEC 1
J 0
(-4925 0);
DISPLAY 0.680851 (-4925 0);
PAINT MONO (-4925 0);
DISPLAY INVISIBLE (-4925 0);
FORCEPROP 0 LAST CDS_SEC 1
J 0
(-4925 0);
DISPLAY 1.021277 (-4925 0);
DISPLAY INVISIBLE (-4925 0);
FORCEADD UNIVERSAL_GND..1
(-4975 -400);
FORCEPROP 3 LASTPIN (-4975 -350) SIG_NAME GND\g
J 0
(-4965 -340);
DISPLAY 0.659574 (-4965 -340);
PAINT MONO (-4965 -340);
DISPLAY INVISIBLE (-4965 -340);
FORCEPROP 1 LAST HDL_POWER GND
J 1
(-4950 -475);
DISPLAY 0.872340 (-4950 -475);
PAINT GREEN (-4950 -475);
DISPLAY INVISIBLE (-4950 -475);
FORCEPROP 2 LAST CDS_LIB logical_power
J 0
(-4975 -400);
DISPLAY INVISIBLE (-4975 -400);
FORCEPROP 1 LAST PATH I185
J 0
(-4900 -400);
DISPLAY 0.872340 (-4900 -400);
PAINT AQUA (-4900 -400);
DISPLAY INVISIBLE (-4900 -400);
FORCEADD UNIVERSAL_POWER..1
(-7800 125);
FORCEPROP 3 LASTPIN (-7800 75) SIG_NAME P3V3_AUX\g
J 0
(-7790 85);
DISPLAY 0.659574 (-7790 85);
PAINT MONO (-7790 85);
DISPLAY INVISIBLE (-7790 85);
FORCEPROP 1 LAST HDL_POWER P3V3_AUX
J 1
(-7800 175);
DISPLAY 0.872340 (-7800 175);
PAINT GREEN (-7800 175);
FORCEPROP 1 LAST PATH I186
J 0
(-7750 150);
DISPLAY 0.872340 (-7750 150);
PAINT AQUA (-7750 150);
DISPLAY INVISIBLE (-7750 150);
FORCEPROP 2 LAST CDS_LIB logical_power
J 0
(-7800 125);
PAINT MONO (-7800 125);
DISPLAY INVISIBLE (-7800 125);
FORCEADD Q_RES..2
(-7800 -125);
FORCEPROP 1 LAST PART_NUMBER CS41002FB09
J 0
(-7760 -250);
DISPLAY 0.510638 (-7760 -250);
DISPLAY INVISIBLE (-7760 -250);
FORCEPROP 1 LAST MATERIAL EMPTY
J 0
(-7760 -200);
DISPLAY 0.510638 (-7760 -200);
PAINT RED (-7760 -200);
FORCEPROP 1 LAST PACK_TYPE 0402LF
J 0
(-7760 -300);
DISPLAY 0.510638 (-7760 -300);
FORCEPROP 1 LAST WATTAGE 1/16W
J 0
(-7760 -150);
DISPLAY 0.510638 (-7760 -150);
FORCEPROP 1 LAST VALUE 100K
J 0
(-7755 -50);
DISPLAY 0.510638 (-7755 -50);
FORCEPROP 1 LAST TOLERANCE 1%
J 0
(-7755 -100);
DISPLAY 0.510638 (-7755 -100);
FORCEPROP 1 LAST $LOCATION R2910
J 0
(-7755 0);
DISPLAY 0.978723 (-7755 0);
FORCEPROP 1 LASTPIN (-7800 -25) $PN 1
J 0
(-7795 -63);
DISPLAY 0.787234 (-7795 -63);
PAINT MONO (-7795 -63);
FORCEPROP 1 LASTPIN (-7800 -225) $PN 2
J 0
(-7795 -215);
DISPLAY 0.787234 (-7795 -215);
PAINT MONO (-7795 -215);
FORCEPROP 1 LAST PATH I187
J 0
(-7750 50);
DISPLAY 0.978723 (-7750 50);
PAINT WHITE (-7750 50);
DISPLAY INVISIBLE (-7750 50);
FORCEPROP 2 LAST CDS_LIB pure_quanta
J 0
(-7800 -125);
DISPLAY INVISIBLE (-7800 -125);
FORCEPROP 0 LAST CDS_LOCATION R2910
J 0
(-7750 50);
DISPLAY 1.021277 (-7750 50);
DISPLAY INVISIBLE (-7750 50);
FORCEPROP 0 LAST $SEC 1
J 0
(-7750 50);
DISPLAY 0.680851 (-7750 50);
PAINT MONO (-7750 50);
DISPLAY INVISIBLE (-7750 50);
FORCEPROP 0 LAST CDS_SEC 1
J 0
(-7750 50);
DISPLAY 1.021277 (-7750 50);
DISPLAY INVISIBLE (-7750 50);
FORCEADD Q_RES..2
(-7775 -600);
FORCEPROP 1 LAST PART_NUMBER CS24702JB10
J 0
(-7735 -775);
DISPLAY 0.638298 (-7735 -775);
DISPLAY INVISIBLE (-7735 -775);
FORCEPROP 1 LAST VALUE 4.7K
J 0
(-7730 -525);
DISPLAY 0.638298 (-7730 -525);
FORCEPROP 1 LAST MATERIAL CHIP
J 0
(-7735 -675);
DISPLAY 0.638298 (-7735 -675);
FORCEPROP 1 LAST TOLERANCE 5%
J 0
(-7730 -575);
DISPLAY 0.638298 (-7730 -575);
FORCEPROP 1 LAST PACK_TYPE 0402LF
J 0
(-7735 -725);
DISPLAY 0.638298 (-7735 -725);
FORCEPROP 1 LAST WATTAGE 1/16W
J 0
(-7735 -625);
DISPLAY 0.638298 (-7735 -625);
FORCEPROP 1 LAST $LOCATION R2918
J 0
(-7730 -475);
DISPLAY 0.638298 (-7730 -475);
FORCEPROP 1 LASTPIN (-7775 -500) $PN 1
J 0
(-7770 -538);
DISPLAY 0.787234 (-7770 -538);
FORCEPROP 1 LASTPIN (-7775 -700) $PN 2
J 0
(-7770 -690);
DISPLAY 0.787234 (-7770 -690);
FORCEPROP 2 LAST CDS_LIB pure_quanta
J 0
(-7775 -600);
PAINT MONO (-7775 -600);
DISPLAY INVISIBLE (-7775 -600);
FORCEPROP 1 LAST PATH I188
J 0
(-7725 -425);
DISPLAY 0.978723 (-7725 -425);
PAINT WHITE (-7725 -425);
DISPLAY INVISIBLE (-7725 -425);
FORCEPROP 2 LAST CDS_LOCATION R2918
J 0
(-7725 -375);
DISPLAY 1.021277 (-7725 -375);
DISPLAY INVISIBLE (-7725 -375);
FORCEPROP 2 LAST $SEC 1
J 0
(-7725 -375);
DISPLAY 0.680851 (-7725 -375);
PAINT MONO (-7725 -375);
DISPLAY INVISIBLE (-7725 -375);
FORCEPROP 2 LAST CDS_SEC 1
J 0
(-7725 -375);
DISPLAY 1.021277 (-7725 -375);
DISPLAY INVISIBLE (-7725 -375);
FORCEADD UNIVERSAL_GND..1
(-7775 -775);
FORCEPROP 3 LASTPIN (-7775 -725) SIG_NAME GND\g
J 0
(-7765 -715);
DISPLAY 0.659574 (-7765 -715);
PAINT MONO (-7765 -715);
DISPLAY INVISIBLE (-7765 -715);
FORCEPROP 1 LAST HDL_POWER GND
J 1
(-7750 -850);
DISPLAY 0.872340 (-7750 -850);
PAINT GREEN (-7750 -850);
DISPLAY INVISIBLE (-7750 -850);
FORCEPROP 2 LAST CDS_LIB logical_power
J 0
(-7775 -775);
DISPLAY INVISIBLE (-7775 -775);
FORCEPROP 1 LAST PATH I189
J 0
(-7700 -775);
DISPLAY 0.872340 (-7700 -775);
PAINT AQUA (-7700 -775);
DISPLAY INVISIBLE (-7700 -775);
FORCEADD OFFPAGE..4
R 2
(-8000 -400);
FORCEPROP 2 LAST $XR0 213 
J 0
(-8282 -400);
DISPLAY 0.638298 (-8282 -400);
PAINT MONO (-8282 -400);
FORCEPROP 2 LAST PATH I190
J 0
(-8250 -350);
DISPLAY 1.021277 (-8250 -350);
DISPLAY INVISIBLE (-8250 -350);
FORCEPROP 2 LAST CDS_LIB standard
J 0
(-8000 -400);
DISPLAY INVISIBLE (-8000 -400);
FORCEPROP 1 LAST COMMENT_BODY TRUE
J 2
(-7975 -500);
DISPLAY 0.872340 (-7975 -500);
PAINT GREEN (-7975 -500);
DISPLAY INVISIBLE (-7975 -500);
FORCEPROP 1 LAST OFFPAGE TRUE
J 2
(-8325 -525);
DISPLAY 0.872340 (-8325 -525);
PAINT GREEN (-8325 -525);
DISPLAY INVISIBLE (-8325 -525);
FORCEADD UNIVERSAL_POWER..1
(-4150 -50);
FORCEPROP 3 LASTPIN (-4150 -100) SIG_NAME P3V3_AUX\g
J 0
(-4140 -90);
DISPLAY 0.659574 (-4140 -90);
PAINT MONO (-4140 -90);
DISPLAY INVISIBLE (-4140 -90);
FORCEPROP 1 LAST HDL_POWER P3V3_AUX
J 1
(-4150 0);
DISPLAY 0.872340 (-4150 0);
PAINT GREEN (-4150 0);
FORCEPROP 1 LAST PATH I191
J 0
(-4100 -25);
DISPLAY 0.872340 (-4100 -25);
PAINT AQUA (-4100 -25);
DISPLAY INVISIBLE (-4100 -25);
FORCEPROP 2 LAST CDS_LIB logical_power
J 0
(-4150 -50);
PAINT MONO (-4150 -50);
DISPLAY INVISIBLE (-4150 -50);
FORCEADD Q_RES..2
(-4150 -300);
FORCEPROP 1 LAST PART_NUMBER CS24702JB10
J 0
(-4110 -475);
DISPLAY 0.638298 (-4110 -475);
DISPLAY INVISIBLE (-4110 -475);
FORCEPROP 1 LAST VALUE 4.7K
J 0
(-4105 -225);
DISPLAY 0.638298 (-4105 -225);
FORCEPROP 1 LAST PACK_TYPE 0402LF
J 0
(-4110 -425);
DISPLAY 0.638298 (-4110 -425);
FORCEPROP 1 LAST MATERIAL EMPTY
J 0
(-4110 -375);
DISPLAY 0.638298 (-4110 -375);
PAINT RED (-4110 -375);
FORCEPROP 1 LAST WATTAGE 1/16W
J 0
(-4110 -325);
DISPLAY 0.638298 (-4110 -325);
FORCEPROP 1 LAST TOLERANCE 5%
J 0
(-4105 -275);
DISPLAY 0.638298 (-4105 -275);
FORCEPROP 1 LAST $LOCATION R2914
J 0
(-4105 -175);
DISPLAY 0.638298 (-4105 -175);
FORCEPROP 1 LASTPIN (-4150 -200) $PN 1
J 0
(-4145 -238);
DISPLAY 0.787234 (-4145 -238);
FORCEPROP 1 LASTPIN (-4150 -400) $PN 2
J 0
(-4145 -390);
DISPLAY 0.787234 (-4145 -390);
FORCEPROP 1 LAST PATH I192
J 0
(-4100 -125);
DISPLAY 0.978723 (-4100 -125);
PAINT WHITE (-4100 -125);
DISPLAY INVISIBLE (-4100 -125);
FORCEPROP 2 LAST CDS_LIB pure_quanta
J 0
(-4150 -300);
PAINT MONO (-4150 -300);
DISPLAY INVISIBLE (-4150 -300);
FORCEPROP 2 LAST CDS_LOCATION R2914
J 0
(-4100 -75);
DISPLAY 1.021277 (-4100 -75);
DISPLAY INVISIBLE (-4100 -75);
FORCEPROP 2 LAST $SEC 1
J 0
(-4100 -75);
DISPLAY 0.680851 (-4100 -75);
PAINT MONO (-4100 -75);
DISPLAY INVISIBLE (-4100 -75);
FORCEPROP 2 LAST CDS_SEC 1
J 0
(-4100 -75);
DISPLAY 1.021277 (-4100 -75);
DISPLAY INVISIBLE (-4100 -75);
FORCEADD OFFPAGE..2
(-2875 -525);
FORCEPROP 2 LAST $XR0 136 
J 0
(-2686 -525);
DISPLAY 0.638298 (-2686 -525);
PAINT MONO (-2686 -525);
FORCEPROP 2 LAST PATH I194
J 0
(-2675 -475);
DISPLAY 1.021277 (-2675 -475);
DISPLAY INVISIBLE (-2675 -475);
FORCEPROP 2 LAST CDS_LIB standard
J 0
(-2875 -525);
DISPLAY INVISIBLE (-2875 -525);
FORCEPROP 1 LAST OFFPAGE TRUE
J 0
(-2550 -650);
DISPLAY 0.872340 (-2550 -650);
PAINT AQUA (-2550 -650);
DISPLAY INVISIBLE (-2550 -650);
FORCEPROP 1 LAST COMMENT_BODY TRUE
J 0
(-2920 -620);
DISPLAY 0.872340 (-2920 -620);
PAINT GREEN (-2920 -620);
DISPLAY INVISIBLE (-2920 -620);
FORCEADD Q_RES..2
(-4125 -800);
FORCEPROP 1 LAST PART_NUMBER CS24702JB10
J 0
(-4085 -975);
DISPLAY 0.638298 (-4085 -975);
DISPLAY INVISIBLE (-4085 -975);
FORCEPROP 1 LAST VALUE 4.7K
J 0
(-4080 -725);
DISPLAY 0.638298 (-4080 -725);
FORCEPROP 1 LAST TOLERANCE 5%
J 0
(-4080 -775);
DISPLAY 0.638298 (-4080 -775);
FORCEPROP 1 LAST MATERIAL CHIP
J 0
(-4085 -875);
DISPLAY 0.638298 (-4085 -875);
FORCEPROP 1 LAST PACK_TYPE 0402LF
J 0
(-4085 -925);
DISPLAY 0.638298 (-4085 -925);
FORCEPROP 1 LAST WATTAGE 1/16W
J 0
(-4085 -825);
DISPLAY 0.638298 (-4085 -825);
FORCEPROP 1 LAST $LOCATION R2932
J 0
(-4080 -675);
DISPLAY 0.978723 (-4080 -675);
FORCEPROP 1 LASTPIN (-4125 -700) $PN 1
J 0
(-4120 -738);
DISPLAY 0.787234 (-4120 -738);
PAINT MONO (-4120 -738);
FORCEPROP 1 LASTPIN (-4125 -900) $PN 2
J 0
(-4120 -890);
DISPLAY 0.787234 (-4120 -890);
PAINT MONO (-4120 -890);
FORCEPROP 2 LAST CDS_LIB pure_quanta
J 0
(-4125 -800);
DISPLAY INVISIBLE (-4125 -800);
FORCEPROP 1 LAST PATH I195
J 0
(-4075 -625);
DISPLAY 0.978723 (-4075 -625);
PAINT WHITE (-4075 -625);
DISPLAY INVISIBLE (-4075 -625);
FORCEPROP 0 LAST CDS_LOCATION R2932
J 0
(-4075 -625);
DISPLAY 1.021277 (-4075 -625);
DISPLAY INVISIBLE (-4075 -625);
FORCEPROP 0 LAST $SEC 1
J 0
(-4075 -625);
DISPLAY 0.680851 (-4075 -625);
PAINT MONO (-4075 -625);
DISPLAY INVISIBLE (-4075 -625);
FORCEPROP 0 LAST CDS_SEC 1
J 0
(-4075 -625);
DISPLAY 1.021277 (-4075 -625);
DISPLAY INVISIBLE (-4075 -625);
FORCEADD UNIVERSAL_GND..1
(-4125 -1025);
FORCEPROP 3 LASTPIN (-4125 -975) SIG_NAME GND\g
J 0
(-4115 -965);
DISPLAY 0.659574 (-4115 -965);
PAINT MONO (-4115 -965);
DISPLAY INVISIBLE (-4115 -965);
FORCEPROP 1 LAST HDL_POWER GND
J 1
(-4100 -1100);
DISPLAY 0.872340 (-4100 -1100);
PAINT GREEN (-4100 -1100);
DISPLAY INVISIBLE (-4100 -1100);
FORCEPROP 2 LAST CDS_LIB logical_power
J 0
(-4125 -1025);
DISPLAY INVISIBLE (-4125 -1025);
FORCEPROP 1 LAST PATH I196
J 0
(-4050 -1025);
DISPLAY 0.872340 (-4050 -1025);
PAINT AQUA (-4050 -1025);
DISPLAY INVISIBLE (-4050 -1025);
FORCEADD Q_RES..1
(-4650 100);
FORCEPROP 1 LAST PART_NUMBER CS04992FB07
J 0
(-4550 75);
DISPLAY 0.404255 (-4550 75);
DISPLAY INVISIBLE (-4550 75);
FORCEPROP 1 LAST MATERIAL CHIP
J 0
(-4800 75);
DISPLAY 0.404255 (-4800 75);
FORCEPROP 1 LAST VALUE 49.9
J 2
(-4425 100);
DISPLAY 0.510638 (-4425 100);
FORCEPROP 1 LAST LOCATION R3468
J 0
(-4875 100);
DISPLAY 0.638298 (-4875 100);
FORCEPROP 1 LASTPIN (-4750 100) $PN 1
J 0
(-4738 112);
DISPLAY 0.787234 (-4738 112);
PAINT MONO (-4738 112);
FORCEPROP 1 LASTPIN (-4550 100) $PN 2
J 0
(-4588 112);
DISPLAY 0.787234 (-4588 112);
PAINT MONO (-4588 112);
FORCEPROP 1 LAST PATH I197
J 0
(-4700 250);
DISPLAY 0.978723 (-4700 250);
PAINT WHITE (-4700 250);
DISPLAY INVISIBLE (-4700 250);
FORCEPROP 2 LAST CDS_LIB pure_quanta
J 0
(-4650 100);
DISPLAY INVISIBLE (-4650 100);
FORCEPROP 1 LAST WATTAGE 1/16W
J 2
(-4350 50);
DISPLAY 0.404255 (-4350 50);
DISPLAY INVISIBLE (-4350 50);
FORCEPROP 1 LAST TOLERANCE 1%
J 0
(-4425 100);
DISPLAY 0.510638 (-4425 100);
DISPLAY INVISIBLE (-4425 100);
FORCEPROP 1 LAST PACK_TYPE 0402LF
J 0
(-4350 100);
DISPLAY 0.510638 (-4350 100);
DISPLAY INVISIBLE (-4350 100);
FORCEPROP 0 LAST $SEC 1
J 0
(-4875 150);
DISPLAY 0.680851 (-4875 150);
PAINT MONO (-4875 150);
DISPLAY INVISIBLE (-4875 150);
FORCEPROP 0 LAST CDS_SEC 1
J 0
(-4875 150);
DISPLAY 1.021277 (-4875 150);
DISPLAY INVISIBLE (-4875 150);
FORCEADD Q_RES..1
(-3875 -525);
FORCEPROP 1 LAST PART_NUMBER CS04992FB07
J 0
(-3775 -550);
DISPLAY 0.404255 (-3775 -550);
DISPLAY INVISIBLE (-3775 -550);
FORCEPROP 1 LAST MATERIAL CHIP
J 0
(-4025 -550);
DISPLAY 0.404255 (-4025 -550);
FORCEPROP 1 LAST VALUE 49.9
J 2
(-3650 -525);
DISPLAY 0.510638 (-3650 -525);
FORCEPROP 1 LAST LOCATION R3515
J 0
(-4100 -525);
DISPLAY 0.638298 (-4100 -525);
FORCEPROP 1 LASTPIN (-3975 -525) $PN 1
J 0
(-3963 -513);
DISPLAY 0.787234 (-3963 -513);
PAINT MONO (-3963 -513);
FORCEPROP 1 LASTPIN (-3775 -525) $PN 2
J 0
(-3813 -513);
DISPLAY 0.787234 (-3813 -513);
PAINT MONO (-3813 -513);
FORCEPROP 2 LAST CDS_LIB pure_quanta
J 0
(-3875 -525);
DISPLAY INVISIBLE (-3875 -525);
FORCEPROP 1 LAST WATTAGE 1/16W
J 2
(-3575 -575);
DISPLAY 0.404255 (-3575 -575);
DISPLAY INVISIBLE (-3575 -575);
FORCEPROP 1 LAST TOLERANCE 1%
J 0
(-3650 -525);
DISPLAY 0.510638 (-3650 -525);
DISPLAY INVISIBLE (-3650 -525);
FORCEPROP 1 LAST PACK_TYPE 0402LF
J 0
(-3575 -525);
DISPLAY 0.510638 (-3575 -525);
DISPLAY INVISIBLE (-3575 -525);
FORCEPROP 1 LAST PATH I198
J 0
(-3925 -375);
DISPLAY 0.978723 (-3925 -375);
PAINT WHITE (-3925 -375);
DISPLAY INVISIBLE (-3925 -375);
FORCEPROP 0 LAST $SEC 1
J 0
(-4100 -475);
DISPLAY 0.680851 (-4100 -475);
PAINT MONO (-4100 -475);
DISPLAY INVISIBLE (-4100 -475);
FORCEPROP 0 LAST CDS_SEC 1
J 0
(-4100 -475);
DISPLAY 1.021277 (-4100 -475);
DISPLAY INVISIBLE (-4100 -475);
FORCEADD Q_RES..1
(-4625 1900);
FORCEPROP 1 LAST PART_NUMBER CS04992FB07
J 0
(-4525 1875);
DISPLAY 0.404255 (-4525 1875);
DISPLAY INVISIBLE (-4525 1875);
FORCEPROP 1 LAST VALUE 49.9
J 2
(-4400 1900);
DISPLAY 0.510638 (-4400 1900);
FORCEPROP 1 LAST MATERIAL CHIP
J 0
(-4775 1875);
DISPLAY 0.404255 (-4775 1875);
FORCEPROP 1 LAST LOCATION R3469
J 0
(-4850 1900);
DISPLAY 0.638298 (-4850 1900);
FORCEPROP 1 LASTPIN (-4725 1900) $PN 1
J 0
(-4713 1912);
DISPLAY 0.787234 (-4713 1912);
PAINT MONO (-4713 1912);
FORCEPROP 1 LASTPIN (-4525 1900) $PN 2
J 0
(-4563 1912);
DISPLAY 0.787234 (-4563 1912);
PAINT MONO (-4563 1912);
FORCEPROP 1 LAST PACK_TYPE 0402LF
J 0
(-4325 1900);
DISPLAY 0.510638 (-4325 1900);
DISPLAY INVISIBLE (-4325 1900);
FORCEPROP 1 LAST TOLERANCE 1%
J 0
(-4400 1900);
DISPLAY 0.510638 (-4400 1900);
DISPLAY INVISIBLE (-4400 1900);
FORCEPROP 1 LAST WATTAGE 1/16W
J 2
(-4325 1850);
DISPLAY 0.404255 (-4325 1850);
DISPLAY INVISIBLE (-4325 1850);
FORCEPROP 2 LAST CDS_LIB pure_quanta
J 0
(-4625 1900);
DISPLAY INVISIBLE (-4625 1900);
FORCEPROP 1 LAST PATH I199
J 0
(-4675 2050);
DISPLAY 0.978723 (-4675 2050);
PAINT WHITE (-4675 2050);
DISPLAY INVISIBLE (-4675 2050);
FORCEPROP 0 LAST $SEC 1
J 0
(-4850 1950);
DISPLAY 0.680851 (-4850 1950);
PAINT MONO (-4850 1950);
DISPLAY INVISIBLE (-4850 1950);
FORCEPROP 0 LAST CDS_SEC 1
J 0
(-4850 1950);
DISPLAY 1.021277 (-4850 1950);
DISPLAY INVISIBLE (-4850 1950);
FORCEADD UNIVERSAL_POWER..1
(-7600 3525);
FORCEPROP 3 LASTPIN (-7600 3475) SIG_NAME P3V3_AUX\g
J 0
(-7590 3485);
DISPLAY 0.659574 (-7590 3485);
PAINT MONO (-7590 3485);
DISPLAY INVISIBLE (-7590 3485);
FORCEPROP 1 LAST HDL_POWER P3V3_AUX
J 1
(-7600 3575);
DISPLAY 0.872340 (-7600 3575);
PAINT GREEN (-7600 3575);
FORCEPROP 1 LAST PATH I20
J 0
(-7550 3550);
DISPLAY 0.872340 (-7550 3550);
PAINT AQUA (-7550 3550);
DISPLAY INVISIBLE (-7550 3550);
FORCEPROP 2 LAST CDS_LIB logical_power
J 0
(-7600 3525);
PAINT MONO (-7600 3525);
DISPLAY INVISIBLE (-7600 3525);
FORCEADD Q_RES..1
(-4625 1250);
FORCEPROP 1 LAST PART_NUMBER CS04992FB07
J 0
(-4525 1225);
DISPLAY 0.404255 (-4525 1225);
DISPLAY INVISIBLE (-4525 1225);
FORCEPROP 1 LAST MATERIAL CHIP
J 0
(-4775 1225);
DISPLAY 0.404255 (-4775 1225);
FORCEPROP 1 LAST VALUE 49.9
J 2
(-4400 1250);
DISPLAY 0.510638 (-4400 1250);
FORCEPROP 1 LAST LOCATION R3391
J 0
(-4850 1250);
DISPLAY 0.638298 (-4850 1250);
FORCEPROP 1 LASTPIN (-4725 1250) $PN 1
J 0
(-4713 1262);
DISPLAY 0.787234 (-4713 1262);
PAINT MONO (-4713 1262);
FORCEPROP 1 LASTPIN (-4525 1250) $PN 2
J 0
(-4563 1262);
DISPLAY 0.787234 (-4563 1262);
PAINT MONO (-4563 1262);
FORCEPROP 1 LAST PATH I200
J 0
(-4675 1400);
DISPLAY 0.978723 (-4675 1400);
PAINT WHITE (-4675 1400);
DISPLAY INVISIBLE (-4675 1400);
FORCEPROP 2 LAST CDS_LIB pure_quanta
J 0
(-4625 1250);
DISPLAY INVISIBLE (-4625 1250);
FORCEPROP 1 LAST WATTAGE 1/16W
J 2
(-4325 1200);
DISPLAY 0.404255 (-4325 1200);
DISPLAY INVISIBLE (-4325 1200);
FORCEPROP 1 LAST TOLERANCE 1%
J 0
(-4400 1250);
DISPLAY 0.510638 (-4400 1250);
DISPLAY INVISIBLE (-4400 1250);
FORCEPROP 1 LAST PACK_TYPE 0402LF
J 0
(-4325 1250);
DISPLAY 0.510638 (-4325 1250);
DISPLAY INVISIBLE (-4325 1250);
FORCEPROP 0 LAST $SEC 1
J 0
(-4850 1300);
DISPLAY 0.680851 (-4850 1300);
PAINT MONO (-4850 1300);
DISPLAY INVISIBLE (-4850 1300);
FORCEPROP 0 LAST CDS_SEC 1
J 0
(-4850 1300);
DISPLAY 1.021277 (-4850 1300);
DISPLAY INVISIBLE (-4850 1300);
FORCEADD Q_RES..1
(-4750 4125);
FORCEPROP 1 LAST PART_NUMBER CS04992FB07
J 0
(-4650 4100);
DISPLAY 0.404255 (-4650 4100);
DISPLAY INVISIBLE (-4650 4100);
FORCEPROP 1 LAST VALUE 49.9
J 2
(-4525 4125);
DISPLAY 0.510638 (-4525 4125);
FORCEPROP 1 LAST MATERIAL CHIP
J 0
(-4900 4100);
DISPLAY 0.404255 (-4900 4100);
FORCEPROP 1 LAST LOCATION R3390
J 0
(-4975 4125);
DISPLAY 0.638298 (-4975 4125);
FORCEPROP 1 LASTPIN (-4850 4125) $PN 1
J 0
(-4838 4137);
DISPLAY 0.787234 (-4838 4137);
PAINT MONO (-4838 4137);
FORCEPROP 1 LASTPIN (-4650 4125) $PN 2
J 0
(-4688 4137);
DISPLAY 0.787234 (-4688 4137);
PAINT MONO (-4688 4137);
FORCEPROP 1 LAST PATH I201
J 0
(-4800 4275);
DISPLAY 0.978723 (-4800 4275);
PAINT WHITE (-4800 4275);
DISPLAY INVISIBLE (-4800 4275);
FORCEPROP 2 LAST CDS_LIB pure_quanta
J 0
(-4750 4125);
DISPLAY INVISIBLE (-4750 4125);
FORCEPROP 1 LAST WATTAGE 1/16W
J 2
(-4450 4075);
DISPLAY 0.404255 (-4450 4075);
DISPLAY INVISIBLE (-4450 4075);
FORCEPROP 1 LAST TOLERANCE 1%
J 0
(-4525 4125);
DISPLAY 0.510638 (-4525 4125);
DISPLAY INVISIBLE (-4525 4125);
FORCEPROP 1 LAST PACK_TYPE 0402LF
J 0
(-4450 4125);
DISPLAY 0.510638 (-4450 4125);
DISPLAY INVISIBLE (-4450 4125);
FORCEPROP 0 LAST $SEC 1
J 0
(-4975 4175);
DISPLAY 0.680851 (-4975 4175);
PAINT MONO (-4975 4175);
DISPLAY INVISIBLE (-4975 4175);
FORCEPROP 0 LAST CDS_SEC 1
J 0
(-4975 4175);
DISPLAY 1.021277 (-4975 4175);
DISPLAY INVISIBLE (-4975 4175);
FORCEADD Q_RES..1
(-4625 3000);
FORCEPROP 1 LAST PART_NUMBER CS04992FB07
J 0
(-4525 2975);
DISPLAY 0.404255 (-4525 2975);
DISPLAY INVISIBLE (-4525 2975);
FORCEPROP 1 LAST VALUE 49.9
J 2
(-4400 3000);
DISPLAY 0.510638 (-4400 3000);
FORCEPROP 1 LAST MATERIAL CHIP
J 0
(-4775 2975);
DISPLAY 0.404255 (-4775 2975);
FORCEPROP 1 LAST LOCATION R3392
J 0
(-4850 3000);
DISPLAY 0.638298 (-4850 3000);
FORCEPROP 1 LASTPIN (-4725 3000) $PN 1
J 0
(-4713 3012);
DISPLAY 0.787234 (-4713 3012);
PAINT MONO (-4713 3012);
FORCEPROP 1 LASTPIN (-4525 3000) $PN 2
J 0
(-4563 3012);
DISPLAY 0.787234 (-4563 3012);
PAINT MONO (-4563 3012);
FORCEPROP 1 LAST PACK_TYPE 0402LF
J 0
(-4325 3000);
DISPLAY 0.510638 (-4325 3000);
DISPLAY INVISIBLE (-4325 3000);
FORCEPROP 1 LAST TOLERANCE 1%
J 0
(-4400 3000);
DISPLAY 0.510638 (-4400 3000);
DISPLAY INVISIBLE (-4400 3000);
FORCEPROP 1 LAST WATTAGE 1/16W
J 2
(-4325 2950);
DISPLAY 0.404255 (-4325 2950);
DISPLAY INVISIBLE (-4325 2950);
FORCEPROP 2 LAST CDS_LIB pure_quanta
J 0
(-4625 3000);
DISPLAY INVISIBLE (-4625 3000);
FORCEPROP 1 LAST PATH I202
J 0
(-4675 3150);
DISPLAY 0.978723 (-4675 3150);
PAINT WHITE (-4675 3150);
DISPLAY INVISIBLE (-4675 3150);
FORCEPROP 0 LAST $SEC 1
J 0
(-4850 3050);
DISPLAY 0.680851 (-4850 3050);
PAINT MONO (-4850 3050);
DISPLAY INVISIBLE (-4850 3050);
FORCEPROP 0 LAST CDS_SEC 1
J 0
(-4850 3050);
DISPLAY 1.021277 (-4850 3050);
DISPLAY INVISIBLE (-4850 3050);
FORCEADD 74LVC2G17GW..1
(-6125 3575);
FORCEPROP 1 LAST PART_NUMBER AL2G0017005
J 0
(-6325 2800);
DISPLAY 0.723404 (-6325 2800);
PAINT GREEN (-6325 2800);
DISPLAY INVISIBLE (-6325 2800);
FORCEPROP 2 LAST PART_TYPE SMLF
J 0
(-6325 2900);
DISPLAY 1.021277 (-6325 2900);
FORCEPROP 2 LAST VALUE 74LVC2G17GW
J 0
(-6325 2850);
DISPLAY 1.021277 (-6325 2850);
FORCEPROP 1 LAST MATERIAL IC
J 0
(-6325 2750);
DISPLAY 0.723404 (-6325 2750);
PAINT GREEN (-6325 2750);
FORCEPROP 1 LAST $LOCATION U253
J 0
(-5898 3335);
DISPLAY 0.723404 (-5898 3335);
PAINT GREEN (-5898 3335);
FORCEPROP 0 LASTPIN (-6500 3700) $PN 1
J 2
(-6510 3710);
DISPLAY 0.680851 (-6510 3710);
PAINT MONO (-6510 3710);
FORCEPROP 0 LASTPIN (-6500 3450) $PN 3
J 2
(-6510 3460);
DISPLAY 0.680851 (-6510 3460);
PAINT MONO (-6510 3460);
FORCEPROP 0 LASTPIN (-5750 3700) $PN 6
J 0
(-5740 3710);
DISPLAY 0.680851 (-5740 3710);
PAINT MONO (-5740 3710);
FORCEPROP 0 LASTPIN (-5750 3450) $PN 4
J 0
(-5740 3460);
DISPLAY 0.680851 (-5740 3460);
PAINT MONO (-5740 3460);
FORCEPROP 0 LASTPIN (-6100 3150) $PN 2
R 1
J 2
(-6110 3140);
DISPLAY 0.680851 (-6110 3140);
PAINT MONO (-6110 3140);
FORCEPROP 0 LASTPIN (-6100 4000) $PN 5
R 1
J 0
(-6110 4010);
DISPLAY 0.680851 (-6110 4010);
PAINT MONO (-6110 4010);
FORCEPROP 1 LAST PATH I26
J 0
(-5900 3300);
DISPLAY 0.723404 (-5900 3300);
PAINT GREEN (-5900 3300);
DISPLAY INVISIBLE (-5900 3300);
FORCEPROP 1 LAST CDS_LMAN_SYM_OUTLINE -225,275,225,-275
J 0
(-6125 3575);
DISPLAY 0.468085 (-6125 3575);
PAINT GREEN (-6125 3575);
DISPLAY INVISIBLE (-6125 3575);
FORCEPROP 1 LAST NEEDS_NO_SIZE TRUE
J 0
(-5900 3574);
DISPLAY 0.468085 (-5900 3574);
PAINT GREEN (-5900 3574);
DISPLAY INVISIBLE (-5900 3574);
FORCEPROP 2 LAST CDS_LIB pure_quanta
J 0
(-6125 3575);
DISPLAY INVISIBLE (-6125 3575);
FORCEPROP 0 LAST CDS_LOCATION U253
J 0
(-5875 3375);
DISPLAY 1.021277 (-5875 3375);
DISPLAY INVISIBLE (-5875 3375);
FORCEPROP 0 LAST $SEC 1
J 0
(-5875 3375);
DISPLAY 0.680851 (-5875 3375);
PAINT MONO (-5875 3375);
DISPLAY INVISIBLE (-5875 3375);
FORCEPROP 0 LAST CDS_SEC 1
J 0
(-5875 3375);
DISPLAY 1.021277 (-5875 3375);
DISPLAY INVISIBLE (-5875 3375);
FORCEADD UNIVERSAL_GND..1
(-6100 2975);
FORCEPROP 3 LASTPIN (-6100 3025) SIG_NAME GND\g
J 0
(-6090 3035);
DISPLAY 0.659574 (-6090 3035);
PAINT MONO (-6090 3035);
DISPLAY INVISIBLE (-6090 3035);
FORCEPROP 1 LAST PATH I27
J 0
(-6025 2975);
DISPLAY 0.872340 (-6025 2975);
PAINT AQUA (-6025 2975);
DISPLAY INVISIBLE (-6025 2975);
FORCEPROP 2 LAST CDS_LIB logical_power
J 0
(-6100 2975);
DISPLAY INVISIBLE (-6100 2975);
FORCEPROP 1 LAST HDL_POWER GND
J 1
(-6075 2900);
DISPLAY 0.872340 (-6075 2900);
PAINT GREEN (-6075 2900);
DISPLAY INVISIBLE (-6075 2900);
FORCEADD UNIVERSAL_GND..1
(-5975 4275);
FORCEPROP 3 LASTPIN (-5975 4325) SIG_NAME GND\g
J 0
(-5965 4335);
DISPLAY 0.659574 (-5965 4335);
PAINT MONO (-5965 4335);
DISPLAY INVISIBLE (-5965 4335);
FORCEPROP 1 LAST HDL_POWER GND
J 1
(-5950 4200);
DISPLAY 0.872340 (-5950 4200);
PAINT GREEN (-5950 4200);
DISPLAY INVISIBLE (-5950 4200);
FORCEPROP 2 LAST CDS_LIB logical_power
J 0
(-5975 4275);
PAINT MONO (-5975 4275);
DISPLAY INVISIBLE (-5975 4275);
FORCEPROP 1 LAST PATH I28
J 0
(-5900 4275);
DISPLAY 0.872340 (-5900 4275);
PAINT AQUA (-5900 4275);
DISPLAY INVISIBLE (-5900 4275);
FORCEADD Q_CAP..1
(-5975 4500);
FORCEPROP 1 LAST PART_NUMBER CH4104K1B00
J 0
(-5925 4350);
DISPLAY 0.510638 (-5925 4350);
DISPLAY INVISIBLE (-5925 4350);
FORCEPROP 1 LAST VALUE 0.1UF
J 0
(-5925 4550);
DISPLAY 0.510638 (-5925 4550);
FORCEPROP 1 LAST VOLTAGE 25V
J 0
(-5925 4500);
DISPLAY 0.510638 (-5925 4500);
FORCEPROP 1 LAST MATERIAL X7R
J 0
(-5925 4400);
DISPLAY 0.510638 (-5925 4400);
FORCEPROP 1 LAST TOLERANCE 10%
J 0
(-5925 4450);
DISPLAY 0.510638 (-5925 4450);
FORCEPROP 1 LAST PACK_TYPE 0402
J 0
(-5925 4300);
DISPLAY 0.510638 (-5925 4300);
FORCEPROP 1 LAST $LOCATION C1958
J 0
(-5925 4600);
DISPLAY 0.787234 (-5925 4600);
FORCEPROP 1 LASTPIN (-5975 4600) $PN 1
J 0
(-5965 4580);
DISPLAY 0.787234 (-5965 4580);
FORCEPROP 1 LASTPIN (-5975 4400) $PN 2
J 0
(-5965 4380);
DISPLAY 0.787234 (-5965 4380);
FORCEPROP 2 LAST CDS_LIB pure_quanta
J 2
(-5975 4500);
PAINT MONO (-5975 4500);
DISPLAY INVISIBLE (-5975 4500);
FORCEPROP 1 LAST PATH I29
J 0
(-5925 4650);
DISPLAY 0.978723 (-5925 4650);
PAINT WHITE (-5925 4650);
DISPLAY INVISIBLE (-5925 4650);
FORCEPROP 2 LAST CDS_LOCATION C1958
J 0
(-5925 4700);
DISPLAY 1.021277 (-5925 4700);
DISPLAY INVISIBLE (-5925 4700);
FORCEPROP 2 LAST $SEC 1
J 0
(-5925 4700);
DISPLAY 0.680851 (-5925 4700);
PAINT MONO (-5925 4700);
DISPLAY INVISIBLE (-5925 4700);
FORCEPROP 2 LAST CDS_SEC 1
J 0
(-5925 4700);
DISPLAY 1.021277 (-5925 4700);
DISPLAY INVISIBLE (-5925 4700);
FORCEADD UNIVERSAL_POWER..1
(-5975 4825);
FORCEPROP 3 LASTPIN (-5975 4775) SIG_NAME P3V3_AUX\g
J 0
(-5965 4785);
DISPLAY 0.659574 (-5965 4785);
PAINT MONO (-5965 4785);
DISPLAY INVISIBLE (-5965 4785);
FORCEPROP 1 LAST HDL_POWER P3V3_AUX
J 1
(-5975 4875);
DISPLAY 0.872340 (-5975 4875);
PAINT GREEN (-5975 4875);
FORCEPROP 2 LAST CDS_LIB logical_power
J 0
(-5975 4825);
PAINT MONO (-5975 4825);
DISPLAY INVISIBLE (-5975 4825);
FORCEPROP 1 LAST PATH I30
J 0
(-5925 4850);
DISPLAY 0.872340 (-5925 4850);
PAINT AQUA (-5925 4850);
DISPLAY INVISIBLE (-5925 4850);
FORCEADD OFFPAGE..2
(-3425 3000);
FORCEPROP 2 LAST $XR0 141 
J 0
(-3236 3000);
DISPLAY 0.638298 (-3236 3000);
PAINT MONO (-3236 3000);
FORCEPROP 1 LAST COMMENT_BODY TRUE
J 0
(-3470 2905);
DISPLAY 0.872340 (-3470 2905);
PAINT GREEN (-3470 2905);
DISPLAY INVISIBLE (-3470 2905);
FORCEPROP 1 LAST OFFPAGE TRUE
J 0
(-3100 2875);
DISPLAY 0.872340 (-3100 2875);
PAINT AQUA (-3100 2875);
DISPLAY INVISIBLE (-3100 2875);
FORCEPROP 2 LAST CDS_LIB standard
J 0
(-3425 3000);
DISPLAY INVISIBLE (-3425 3000);
FORCEPROP 2 LAST PATH I67
J 0
(-3225 3050);
DISPLAY 1.021277 (-3225 3050);
DISPLAY INVISIBLE (-3225 3050);
FORCEADD Q_RES..2
(-7575 2875);
FORCEPROP 1 LAST PART_NUMBER CS41002FB09
J 0
(-7535 2750);
DISPLAY 0.510638 (-7535 2750);
DISPLAY INVISIBLE (-7535 2750);
FORCEPROP 1 LAST PACK_TYPE 0402LF
J 0
(-7535 2700);
DISPLAY 0.510638 (-7535 2700);
FORCEPROP 1 LAST MATERIAL CHIP
J 0
(-7535 2800);
DISPLAY 0.510638 (-7535 2800);
FORCEPROP 1 LAST TOLERANCE 1%
J 0
(-7530 2900);
DISPLAY 0.510638 (-7530 2900);
FORCEPROP 1 LAST VALUE 100K
J 0
(-7530 2950);
DISPLAY 0.510638 (-7530 2950);
FORCEPROP 1 LAST WATTAGE 1/16W
J 0
(-7535 2850);
DISPLAY 0.510638 (-7535 2850);
FORCEPROP 1 LAST $LOCATION R3452
J 0
(-7530 3000);
DISPLAY 0.978723 (-7530 3000);
FORCEPROP 1 LASTPIN (-7575 2975) $PN 1
J 0
(-7570 2937);
DISPLAY 0.787234 (-7570 2937);
PAINT MONO (-7570 2937);
FORCEPROP 1 LASTPIN (-7575 2775) $PN 2
J 0
(-7570 2785);
DISPLAY 0.787234 (-7570 2785);
PAINT MONO (-7570 2785);
FORCEPROP 2 LAST CDS_LIB pure_quanta
J 0
(-7575 2875);
DISPLAY INVISIBLE (-7575 2875);
FORCEPROP 1 LAST PATH I95
J 0
(-7525 3050);
DISPLAY 0.978723 (-7525 3050);
PAINT WHITE (-7525 3050);
DISPLAY INVISIBLE (-7525 3050);
FORCEPROP 0 LAST CDS_LOCATION R3452
J 0
(-7525 3050);
DISPLAY 1.021277 (-7525 3050);
DISPLAY INVISIBLE (-7525 3050);
FORCEPROP 0 LAST $SEC 1
J 0
(-7525 3050);
DISPLAY 0.680851 (-7525 3050);
PAINT MONO (-7525 3050);
DISPLAY INVISIBLE (-7525 3050);
FORCEPROP 0 LAST CDS_SEC 1
J 0
(-7525 3050);
DISPLAY 1.021277 (-7525 3050);
DISPLAY INVISIBLE (-7525 3050);
FORCEADD QUANTA_TITLE_BLOCK_C..1
(-1200 -1575);
FORCEPROP 0 LAST CDS_CON_LAST_MODIFIED Fri Aug 25 14:02:11 2023
J 0
(-3085 -1560);
PAINT MONO (-3085 -1560);
DISPLAY INVISIBLE (-3085 -1560);
FORCEPROP 2 LAST CUSTOM_TXT_CDS <XR_PAGE_TITLE>
J 0
(-9090 3675);
DISPLAY 0.638298 (-9090 3675);
PAINT PINK (-9090 3675);
DISPLAY INVISIBLE (-9090 3675);
FORCEPROP 2 LAST CUSTOM_TXT_CDS <CON_LAST_MODIFIED>
J 0
(-3085 -1560);
DISPLAY 0.978723 (-3085 -1560);
FORCEPROP 2 LAST CUSTOM_TXT_CDS <NAME_1>
J 0
(-4375 -1400);
FORCEPROP 2 LAST CUSTOM_TXT_CDS <NAME_2>
J 0
(-4375 -1525);
FORCEPROP 2 LAST CUSTOM_TXT_CDS <Q_PROJ>
J 0
(-3582 -1473);
DISPLAY 1.212766 (-3582 -1473);
FORCEPROP 2 LAST CUSTOM_TXT_CDS <Q_NUMBER>
J 0
(-2603 -1472);
DISPLAY 1.212766 (-2603 -1472);
FORCEPROP 2 LAST CUSTOM_TXT_CDS <CON_PAGE_NUM> OF <CON_TOTAL_PAGES>
J 0
(-1646 -1557);
DISPLAY 0.978723 (-1646 -1557);
FORCEPROP 2 LAST CUSTOM_TXT_CDS <Q_REV>
J 0
(-1384 -1472);
DISPLAY 1.212766 (-1384 -1472);
FORCEPROP 1 LAST Q_TITLE EXAMAX_ISO (5/7)
J 0
(-10450 -1525);
DISPLAY 2.446809 (-10450 -1525);
PAINT GREEN (-10450 -1525);
FORCEPROP 1 LAST Q_DEPT 
J 1
(-4963 -1526);
DISPLAY 1.957447 (-4963 -1526);
PAINT GREEN (-4963 -1526);
FORCEPROP 2 LAST CDS_XR_PAGE_TITLE CR-149 : @S9S_MB_2U_LIB.S9S_MB_2U(SCH_1):PAGE149
J 0
(-9090 3675);
DISPLAY 0.638298 (-9090 3675);
PAINT PINK (-9090 3675);
DISPLAY INVISIBLE (-9090 3675);
FORCEPROP 2 LAST CDS_LIB pure_quanta
J 0
(-1200 -1575);
PAINT MONO (-1200 -1575);
DISPLAY INVISIBLE (-1200 -1575);
FORCEPROP 1 LAST CDS_LMAN_SYM_OUTLINE -9475,6775,100,-125
J 0
(-1200 -1575);
DISPLAY 0.468085 (-1200 -1575);
PAINT GREEN (-1200 -1575);
DISPLAY INVISIBLE (-1200 -1575);
FORCEPROP 1 LAST COMMENT_BODY TRUE
J 0
(-1188 -1588);
DISPLAY 0.978723 (-1188 -1588);
PAINT GREEN (-1188 -1588);
DISPLAY INVISIBLE (-1188 -1588);
FORCEPROP 2 LAST PAGE_BORDER TRUE
J 0
(-9090 3675);
DISPLAY 0.638298 (-9090 3675);
PAINT PINK (-9090 3675);
DISPLAY INVISIBLE (-9090 3675);
FORCEADD DNS..2
(-7800 -150);
PAINT RED (-7800 -150);
FORCEPROP 2 LAST CDS_LIB mstr_misc
J 0
(-7800 -150);
DISPLAY INVISIBLE (-7800 -150);
FORCEPROP 1 LAST COMMENT_BODY TRUE
J 0
(-7800 -150);
DISPLAY INVISIBLE (-7800 -150);
FORCEADD DNS..2
(-4150 -325);
PAINT RED (-4150 -325);
FORCEPROP 1 LAST COMMENT_BODY TRUE
J 0
(-4150 -325);
DISPLAY INVISIBLE (-4150 -325);
FORCEPROP 2 LAST CDS_LIB mstr_misc
J 0
(-4150 -325);
DISPLAY INVISIBLE (-4150 -325);
FORCEADD DNS..2
(-7600 3325);
PAINT RED (-7600 3325);
FORCEPROP 1 LAST COMMENT_BODY TRUE
J 0
(-7600 3325);
DISPLAY INVISIBLE (-7600 3325);
FORCEPROP 2 LAST CDS_LIB mstr_misc
J 0
(-7600 3325);
DISPLAY INVISIBLE (-7600 3325);
FORCEADD DNS..2
(-7600 4375);
PAINT RED (-7600 4375);
FORCEPROP 1 LAST COMMENT_BODY TRUE
J 0
(-7600 4375);
DISPLAY INVISIBLE (-7600 4375);
FORCEPROP 2 LAST CDS_LIB mstr_misc
J 0
(-7600 4375);
DISPLAY INVISIBLE (-7600 4375);
FORCEADD DNS..2
(-4975 3200);
PAINT RED (-4975 3200);
FORCEPROP 1 LAST COMMENT_BODY TRUE
J 0
(-4975 3200);
DISPLAY INVISIBLE (-4975 3200);
FORCEPROP 2 LAST CDS_LIB mstr_misc
J 0
(-4975 3200);
DISPLAY INVISIBLE (-4975 3200);
FORCEADD DNS..2
(-5000 4400);
PAINT RED (-5000 4400);
FORCEPROP 1 LAST COMMENT_BODY TRUE
J 0
(-5000 4400);
DISPLAY INVISIBLE (-5000 4400);
FORCEPROP 2 LAST CDS_LIB mstr_misc
J 0
(-5000 4400);
DISPLAY INVISIBLE (-5000 4400);
WIRE 16 -1 (-4975 3325)(-4975 3475);
WIRE 16 -1 (-4150 -100)(-4150 -200);
WIRE 16 -1 (-7600 3475)(-7600 3450);
WIRE 16 -1 (-6075 2450)(-6075 2375);
WIRE 16 -1 (-6175 575)(-6175 500);
WIRE 16 -1 (-7800 75)(-7800 -25);
WIRE 16 -1 (-7600 4600)(-7600 4500);
WIRE 16 -1 (-5975 4775)(-5975 4700);
WIRE 16 -1 (-5000 4625)(-5000 4525);
WIRE 16 -1 (-4125 -900)(-4125 -975);
WIRE 16 -1 (-7775 -725)(-7775 -700);
WIRE 16 -1 (-7575 2675)(-7575 2775);
WIRE 16 -1 (-7575 3775)(-7575 3825);
WIRE 16 -1 (-6225 1150)(-6225 1100);
WIRE 16 -1 (-6075 2075)(-6075 2000);
WIRE 16 -1 (-6300 -700)(-6300 -800);
WIRE 16 -1 (-4975 -275)(-4975 -350);
WIRE 16 -1 (-6175 200)(-6175 125);
WIRE 16 -1 (-4950 875)(-4950 800);
WIRE 16 -1 (-4950 1525)(-4950 1450);
WIRE 16 -1 (-6100 3150)(-6100 3025);
WIRE 16 -1 (-4950 2625)(-4950 2550);
WIRE 16 -1 (-4975 3725)(-4975 3675);
WIRE 16 -1 (-5975 4400)(-5975 4325);
WIRE 16 -1 (-3525 4125)(-4650 4125);
FORCEPROP 2 LAST SIG_NAME GPU_FPGA_BOOT_EN_BUF
J 0
(-4460 4135);
DISPLAY 0.808511 (-4460 4135);
WIRE 16 -1 (-5975 4700)(-5975 4600);
WIRE 16 -1 (-5975 4700)(-6100 4700);
WIRE 16 -1 (-6100 4000)(-6100 4700);
WIRE 16 -1 (-4975 3925)(-4975 4125);
WIRE 16 -1 (-4975 4125)(-4850 4125);
WIRE 16 -1 (-5000 4325)(-5000 4125);
WIRE 16 -1 (-5000 4125)(-4975 4125);
WIRE 16 -1 (-5750 4125)(-5750 3700);
WIRE 16 -1 (-5750 4125)(-5000 4125);
FORCEPROP 2 LAST SIG_NAME GPU_FPGA_BOOT_EN_BUF_R
J 0
(-5735 4135);
DISPLAY 0.638298 (-5735 4135);
WIRE 16 -1 (-5750 3000)(-5750 3450);
WIRE 16 -1 (-5750 3000)(-4975 3000);
FORCEPROP 2 LAST SIG_NAME GPU_BASE_STBY_EN_BUF_R
J 0
(-5735 3010);
DISPLAY 0.638298 (-5735 3010);
WIRE 16 -1 (-4975 3125)(-4975 3000);
WIRE 16 -1 (-4975 3000)(-4950 3000);
WIRE 16 -1 (-4950 3000)(-4725 3000);
WIRE 16 -1 (-4950 2825)(-4950 3000);
WIRE 16 -1 (-3475 3000)(-4525 3000);
FORCEPROP 2 LAST SIG_NAME GPU_BASE_STBY_EN_BUF
J 0
(-4310 3010);
DISPLAY 0.808511 (-4310 3010);
WIRE 16 -1 (-3475 1900)(-4525 1900);
FORCEPROP 2 LAST SIG_NAME RST_PERST_0_SWB_BUF_N
J 0
(-4310 1910);
DISPLAY 0.808511 (-4310 1910);
WIRE 16 -1 (-5875 1250)(-5875 1450);
WIRE 16 -1 (-5875 1250)(-4950 1250);
FORCEPROP 2 LAST SIG_NAME RST_PERST_1_SWB_BUF_R_N
J 0
(-5860 1260);
DISPLAY 0.638298 (-5860 1260);
WIRE 16 -1 (-4950 1250)(-4725 1250);
WIRE 16 -1 (-4950 1075)(-4950 1250);
WIRE 16 -1 (-3475 1250)(-4525 1250);
FORCEPROP 2 LAST SIG_NAME RST_PERST_1_SWB_BUF_N
J 0
(-4310 1260);
DISPLAY 0.808511 (-4310 1260);
WIRE 16 -1 (-5875 1900)(-5875 1700);
WIRE 16 -1 (-5875 1900)(-4950 1900);
FORCEPROP 2 LAST SIG_NAME RST_PERST_0_SWB_BUF_R_N
J 0
(-5860 1910);
DISPLAY 0.638298 (-5860 1910);
WIRE 16 -1 (-4950 1900)(-4725 1900);
WIRE 16 -1 (-4950 1725)(-4950 1900);
WIRE 16 -1 (-2925 -525)(-3775 -525);
FORCEPROP 2 LAST SIG_NAME FM_SWB_PWR_EN_R_BUF
J 0
(-3610 -515);
DISPLAY 0.808511 (-3610 -515);
WIRE 16 -1 (-4125 -525)(-4125 -700);
WIRE 16 -1 (-4125 -525)(-3975 -525);
WIRE 16 -1 (-4150 -525)(-4125 -525);
WIRE 16 -1 (-4150 -400)(-4150 -525);
WIRE 16 -1 (-4150 -525)(-5950 -525);
FORCEPROP 2 LAST SIG_NAME FM_SWB_PWR_EN_R1_BUF
J 0
(-4985 -515);
DISPLAY 0.808511 (-4985 -515);
WIRE 16 -1 (-5950 -400)(-5950 -525);
WIRE 16 -1 (-5950 -150)(-5950 100);
WIRE 16 -1 (-4975 100)(-5950 100);
FORCEPROP 2 LAST SIG_NAME RST_PERST_2_SWB_BUF_R_N
J 0
(-5885 110);
DISPLAY 0.638298 (-5885 110);
WIRE 16 -1 (-4975 100)(-4750 100);
WIRE 16 -1 (-4975 -75)(-4975 100);
WIRE 16 -1 (-3475 100)(-4550 100);
FORCEPROP 2 LAST SIG_NAME RST_PERST_2_SWB_BUF_N
J 0
(-4335 110);
DISPLAY 0.808511 (-4335 110);
WIRE 16 -1 (-6175 500)(-6175 400);
WIRE 16 -1 (-6175 500)(-6300 500);
WIRE 16 -1 (-6300 150)(-6300 500);
WIRE 16 -1 (-7100 1700)(-8250 1700);
FORCEPROP 2 LAST SIG_NAME RST_PERST_SWB_R_N
J 0
(-7985 1710);
DISPLAY 0.808511 (-7985 1710);
WIRE 16 -1 (-6625 1700)(-7100 1700);
WIRE 16 -1 (-7100 -150)(-6700 -150);
WIRE 16 -1 (-7100 1450)(-7100 -150);
WIRE 16 -1 (-7100 1700)(-7100 1450);
WIRE 16 -1 (-7100 1450)(-6625 1450);
WIRE 16 -1 (-6225 2000)(-6225 2375);
WIRE 16 -1 (-6075 2375)(-6225 2375);
WIRE 16 -1 (-6075 2375)(-6075 2275);
WIRE 16 -1 (-6500 4125)(-6500 3700);
WIRE 16 -1 (-7575 4025)(-7575 4125);
WIRE 16 -1 (-6500 4125)(-7575 4125);
FORCEPROP 2 LAST SIG_NAME GPU_FPGA_BOOT_EN
J 0
(-7535 4135);
DISPLAY 0.808511 (-7535 4135);
WIRE 16 -1 (-7600 4125)(-7800 4125);
WIRE 16 -1 (-7575 4125)(-7600 4125);
WIRE 16 -1 (-7600 4300)(-7600 4125);
WIRE 16 -1 (-7600 3075)(-7750 3075);
WIRE 16 -1 (-7600 3250)(-7600 3075);
WIRE 16 -1 (-7575 3075)(-7575 2975);
WIRE 16 -1 (-7575 3075)(-7600 3075);
WIRE 16 -1 (-6500 3075)(-7575 3075);
FORCEPROP 2 LAST SIG_NAME GPU_BASE_STBY_EN
J 0
(-7435 3085);
DISPLAY 0.808511 (-7435 3085);
WIRE 16 -1 (-6500 3450)(-6500 3075);
WIRE 16 -1 (-7800 -400)(-7950 -400);
WIRE 16 -1 (-7800 -225)(-7800 -400);
WIRE 16 -1 (-7800 -400)(-7775 -400);
WIRE 16 -1 (-7775 -400)(-6700 -400);
FORCEPROP 2 LAST SIG_NAME FM_SWB_PWR_EN_R
J 0
(-7735 -390);
DISPLAY 0.808511 (-7735 -390);
WIRE 16 -1 (-7775 -500)(-7775 -400);
DOT 1 (-7775 -400);
DOT 1 (-4975 4125);
DOT 1 (-7575 3075);
DOT 1 (-7575 4125);
DOT 1 (-6075 2375);
DOT 1 (-5975 4700);
DOT 1 (-5000 4125);
DOT 1 (-4975 3000);
DOT 1 (-4950 3000);
DOT 1 (-4950 1900);
DOT 1 (-4950 1250);
DOT 1 (-4975 100);
DOT 1 (-6175 500);
DOT 1 (-7600 4125);
DOT 1 (-7600 3075);
DOT 1 (-7100 1700);
DOT 1 (-7100 1450);
DOT 1 (-4150 -525);
DOT 1 (-7800 -400);
DOT 1 (-4125 -525);
FORCENOTE
PUSH-PULL OUTPUT
(-6425 2675) 0;
DISPLAY LEFT (-6425 2675);
DISPLAY 1.021277 (-6425 2675);
PAINT WHITE (-6425 2675);
FORCENOTE
PUSH-PULL OUTPUT
(-6650 -925) 0;
DISPLAY LEFT (-6650 -925);
DISPLAY 1.021277 (-6650 -925);
PAINT WHITE (-6650 -925);
FORCENOTE
PUSH-PULL OUTPUT
(-6500 975) 0;
DISPLAY LEFT (-6500 975);
DISPLAY 1.021277 (-6500 975);
PAINT WHITE (-6500 975);
FORCENOTE
2021014 MODIFY FOR GT
(-10325 4950) 0;
DISPLAY LEFT (-10325 4950);
DISPLAY 2.510638 (-10325 4950);
PAINT PINK (-10325 4950);
QUIT
